FILE_TYPE = MACRO_DRAWING;
SET COLOR_WIRE YELLOW;
SET COLOR_PROP MONO;
SET COLOR_DOT WHITE;
SET COLOR_ARC YELLOW;
SET COLOR_BODY GREEN;
SET COLOR_NOTE MONO;
SET PROP_DISPLAY VALUE;
SET PAGE_NUMBER P48;
FORCEADD OFFPAGE..3
(1600 5200);
FORCEPROP 2 LAST $XR0 25 
J 0
(1814 5200);
DISPLAY 0.638298 (1814 5200);
PAINT MONO (1814 5200);
FORCEPROP 2 LAST $XR1 47 
J 0
(1904 5200);
DISPLAY 0.638298 (1904 5200);
PAINT MONO (1904 5200);
FORCEPROP 2 LAST CDS_LIB mstr_standard
J 0
(1600 5200);
DISPLAY 0.787234 (1600 5200);
PAINT MONO (1600 5200);
DISPLAY INVISIBLE (1600 5200);
FORCEPROP 1 LAST OFFPAGE TRUE
J 0
(1925 5075);
DISPLAY 0.936170 (1925 5075);
PAINT GREEN (1925 5075);
DISPLAY INVISIBLE (1925 5075);
FORCEPROP 1 LAST COMMENT_BODY TRUE
J 0
(1550 5100);
DISPLAY 0.936170 (1550 5100);
PAINT GREEN (1550 5100);
DISPLAY INVISIBLE (1550 5100);
FORCEPROP 2 LAST PATH I1
J 0
(1800 5275);
DISPLAY 0.787234 (1800 5275);
PAINT MONO (1800 5275);
DISPLAY INVISIBLE (1800 5275);
FORCEADD TAP..6
R 2
(700 4850);
FORCEPROP 3 LASTPIN (650 4850) SIG_NAME M_C_DQS_DP<14>
J 0
(660 4860);
DISPLAY 0.659574 (660 4860);
PAINT MONO (660 4860);
DISPLAY INVISIBLE (660 4860);
FORCEPROP 1 LASTPIN (650 4850) BN 14
J 2
(700 4860);
DISPLAY 0.617021 (700 4860);
PAINT PINK (700 4860);
FORCEPROP 2 LAST CDS_LIB mstr_standard
J 0
(700 4850);
DISPLAY 0.787234 (700 4850);
PAINT MONO (700 4850);
DISPLAY INVISIBLE (700 4850);
FORCEPROP 1 LAST BODY_TYPE PLUMBING
J 2
(700 4800);
DISPLAY 1.234043 (700 4800);
PAINT GREEN (700 4800);
DISPLAY INVISIBLE (700 4800);
FORCEPROP 1 LAST HDL_TAP TRUE
J 2
(375 4725);
DISPLAY 1.234043 (375 4725);
PAINT WHITE (375 4725);
DISPLAY INVISIBLE (375 4725);
FORCEPROP 1 LAST PATH I10
J 2
(700 4850);
DISPLAY 0.936170 (700 4850);
PAINT GREEN (700 4850);
DISPLAY INVISIBLE (700 4850);
FORCEADD TAP..6
R 2
(-1650 2100);
FORCEPROP 3 LASTPIN (-1700 2100) SIG_NAME M_C_DQ<8>
J 0
(-1690 2110);
DISPLAY 0.659574 (-1690 2110);
PAINT MONO (-1690 2110);
DISPLAY INVISIBLE (-1690 2110);
FORCEPROP 1 LASTPIN (-1700 2100) BN 8
J 2
(-1650 2110);
DISPLAY 0.617021 (-1650 2110);
PAINT PINK (-1650 2110);
FORCEPROP 2 LAST CDS_LIB mstr_standard
J 2
(-1650 2100);
DISPLAY 0.787234 (-1650 2100);
PAINT MONO (-1650 2100);
DISPLAY INVISIBLE (-1650 2100);
FORCEPROP 1 LAST BODY_TYPE PLUMBING
J 2
(-1650 2050);
DISPLAY 1.234043 (-1650 2050);
PAINT GREEN (-1650 2050);
DISPLAY INVISIBLE (-1650 2050);
FORCEPROP 1 LAST HDL_TAP TRUE
J 2
(-1975 1975);
DISPLAY 1.234043 (-1975 1975);
PAINT GREEN (-1975 1975);
DISPLAY INVISIBLE (-1975 1975);
FORCEPROP 1 LAST PATH I100
J 2
(-1650 2100);
DISPLAY 0.936170 (-1650 2100);
PAINT GREEN (-1650 2100);
DISPLAY INVISIBLE (-1650 2100);
FORCEADD TAP..6
R 2
(-1650 2200);
FORCEPROP 3 LASTPIN (-1700 2200) SIG_NAME M_C_DQ<10>
J 0
(-1690 2210);
DISPLAY 0.659574 (-1690 2210);
PAINT MONO (-1690 2210);
DISPLAY INVISIBLE (-1690 2210);
FORCEPROP 1 LASTPIN (-1700 2200) BN 10
J 2
(-1650 2210);
DISPLAY 0.617021 (-1650 2210);
PAINT PINK (-1650 2210);
FORCEPROP 2 LAST CDS_LIB mstr_standard
J 2
(-1650 2200);
DISPLAY 0.787234 (-1650 2200);
PAINT MONO (-1650 2200);
DISPLAY INVISIBLE (-1650 2200);
FORCEPROP 1 LAST BODY_TYPE PLUMBING
J 2
(-1650 2150);
DISPLAY 1.234043 (-1650 2150);
PAINT GREEN (-1650 2150);
DISPLAY INVISIBLE (-1650 2150);
FORCEPROP 1 LAST HDL_TAP TRUE
J 2
(-1975 2075);
DISPLAY 1.234043 (-1975 2075);
PAINT GREEN (-1975 2075);
DISPLAY INVISIBLE (-1975 2075);
FORCEPROP 1 LAST PATH I101
J 2
(-1650 2200);
DISPLAY 0.936170 (-1650 2200);
PAINT GREEN (-1650 2200);
DISPLAY INVISIBLE (-1650 2200);
FORCEADD TAP..6
R 2
(-1650 2150);
FORCEPROP 3 LASTPIN (-1700 2150) SIG_NAME M_C_DQ<9>
J 0
(-1690 2160);
DISPLAY 0.659574 (-1690 2160);
PAINT MONO (-1690 2160);
DISPLAY INVISIBLE (-1690 2160);
FORCEPROP 1 LASTPIN (-1700 2150) BN 9
J 2
(-1650 2160);
DISPLAY 0.617021 (-1650 2160);
PAINT PINK (-1650 2160);
FORCEPROP 2 LAST CDS_LIB mstr_standard
J 2
(-1650 2150);
DISPLAY 0.787234 (-1650 2150);
PAINT MONO (-1650 2150);
DISPLAY INVISIBLE (-1650 2150);
FORCEPROP 1 LAST BODY_TYPE PLUMBING
J 2
(-1650 2100);
DISPLAY 1.234043 (-1650 2100);
PAINT GREEN (-1650 2100);
DISPLAY INVISIBLE (-1650 2100);
FORCEPROP 1 LAST HDL_TAP TRUE
J 2
(-1975 2025);
DISPLAY 1.234043 (-1975 2025);
PAINT GREEN (-1975 2025);
DISPLAY INVISIBLE (-1975 2025);
FORCEPROP 1 LAST PATH I102
J 2
(-1650 2150);
DISPLAY 0.936170 (-1650 2150);
PAINT GREEN (-1650 2150);
DISPLAY INVISIBLE (-1650 2150);
FORCEADD TAP..6
R 2
(-1650 1950);
FORCEPROP 3 LASTPIN (-1700 1950) SIG_NAME M_C_DQ<5>
J 0
(-1690 1960);
DISPLAY 0.659574 (-1690 1960);
PAINT MONO (-1690 1960);
DISPLAY INVISIBLE (-1690 1960);
FORCEPROP 1 LASTPIN (-1700 1950) BN 5
J 2
(-1650 1960);
DISPLAY 0.617021 (-1650 1960);
PAINT PINK (-1650 1960);
FORCEPROP 2 LAST CDS_LIB mstr_standard
J 2
(-1650 1950);
DISPLAY 0.787234 (-1650 1950);
PAINT MONO (-1650 1950);
DISPLAY INVISIBLE (-1650 1950);
FORCEPROP 1 LAST BODY_TYPE PLUMBING
J 2
(-1650 1900);
DISPLAY 1.234043 (-1650 1900);
PAINT GREEN (-1650 1900);
DISPLAY INVISIBLE (-1650 1900);
FORCEPROP 1 LAST HDL_TAP TRUE
J 2
(-1975 1825);
DISPLAY 1.234043 (-1975 1825);
PAINT GREEN (-1975 1825);
DISPLAY INVISIBLE (-1975 1825);
FORCEPROP 1 LAST PATH I103
J 2
(-1650 1950);
DISPLAY 0.936170 (-1650 1950);
PAINT GREEN (-1650 1950);
DISPLAY INVISIBLE (-1650 1950);
FORCEADD TAP..6
R 2
(-1650 2000);
FORCEPROP 3 LASTPIN (-1700 2000) SIG_NAME M_C_DQ<6>
J 0
(-1690 2010);
DISPLAY 0.659574 (-1690 2010);
PAINT MONO (-1690 2010);
DISPLAY INVISIBLE (-1690 2010);
FORCEPROP 1 LASTPIN (-1700 2000) BN 6
J 2
(-1650 2010);
DISPLAY 0.617021 (-1650 2010);
PAINT PINK (-1650 2010);
FORCEPROP 2 LAST CDS_LIB mstr_standard
J 2
(-1650 2000);
DISPLAY 0.787234 (-1650 2000);
PAINT MONO (-1650 2000);
DISPLAY INVISIBLE (-1650 2000);
FORCEPROP 1 LAST BODY_TYPE PLUMBING
J 2
(-1650 1950);
DISPLAY 1.234043 (-1650 1950);
PAINT GREEN (-1650 1950);
DISPLAY INVISIBLE (-1650 1950);
FORCEPROP 1 LAST HDL_TAP TRUE
J 2
(-1975 1875);
DISPLAY 1.234043 (-1975 1875);
PAINT GREEN (-1975 1875);
DISPLAY INVISIBLE (-1975 1875);
FORCEPROP 1 LAST PATH I104
J 2
(-1650 2000);
DISPLAY 0.936170 (-1650 2000);
PAINT GREEN (-1650 2000);
DISPLAY INVISIBLE (-1650 2000);
FORCEADD TAP..6
R 2
(-1650 2050);
FORCEPROP 3 LASTPIN (-1700 2050) SIG_NAME M_C_DQ<7>
J 0
(-1690 2060);
DISPLAY 0.659574 (-1690 2060);
PAINT MONO (-1690 2060);
DISPLAY INVISIBLE (-1690 2060);
FORCEPROP 1 LASTPIN (-1700 2050) BN 7
J 2
(-1650 2060);
DISPLAY 0.617021 (-1650 2060);
PAINT PINK (-1650 2060);
FORCEPROP 2 LAST CDS_LIB mstr_standard
J 2
(-1650 2050);
DISPLAY 0.787234 (-1650 2050);
PAINT MONO (-1650 2050);
DISPLAY INVISIBLE (-1650 2050);
FORCEPROP 1 LAST BODY_TYPE PLUMBING
J 2
(-1650 2000);
DISPLAY 1.234043 (-1650 2000);
PAINT GREEN (-1650 2000);
DISPLAY INVISIBLE (-1650 2000);
FORCEPROP 1 LAST HDL_TAP TRUE
J 2
(-1975 1925);
DISPLAY 1.234043 (-1975 1925);
PAINT GREEN (-1975 1925);
DISPLAY INVISIBLE (-1975 1925);
FORCEPROP 1 LAST PATH I105
J 2
(-1650 2050);
DISPLAY 0.936170 (-1650 2050);
PAINT GREEN (-1650 2050);
DISPLAY INVISIBLE (-1650 2050);
FORCEADD TAP..6
R 2
(-1650 1900);
FORCEPROP 3 LASTPIN (-1700 1900) SIG_NAME M_C_DQ<4>
J 0
(-1690 1910);
DISPLAY 0.659574 (-1690 1910);
PAINT MONO (-1690 1910);
DISPLAY INVISIBLE (-1690 1910);
FORCEPROP 1 LASTPIN (-1700 1900) BN 4
J 2
(-1650 1910);
DISPLAY 0.617021 (-1650 1910);
PAINT PINK (-1650 1910);
FORCEPROP 2 LAST CDS_LIB mstr_standard
J 2
(-1650 1900);
DISPLAY 0.787234 (-1650 1900);
PAINT MONO (-1650 1900);
DISPLAY INVISIBLE (-1650 1900);
FORCEPROP 1 LAST BODY_TYPE PLUMBING
J 2
(-1650 1850);
DISPLAY 1.234043 (-1650 1850);
PAINT GREEN (-1650 1850);
DISPLAY INVISIBLE (-1650 1850);
FORCEPROP 1 LAST HDL_TAP TRUE
J 2
(-1975 1775);
DISPLAY 1.234043 (-1975 1775);
PAINT GREEN (-1975 1775);
DISPLAY INVISIBLE (-1975 1775);
FORCEPROP 1 LAST PATH I106
J 2
(-1650 1900);
DISPLAY 0.936170 (-1650 1900);
PAINT GREEN (-1650 1900);
DISPLAY INVISIBLE (-1650 1900);
FORCEADD TAP..6
R 2
(-1650 1850);
FORCEPROP 3 LASTPIN (-1700 1850) SIG_NAME M_C_DQ<3>
J 0
(-1690 1860);
DISPLAY 0.659574 (-1690 1860);
PAINT MONO (-1690 1860);
DISPLAY INVISIBLE (-1690 1860);
FORCEPROP 1 LASTPIN (-1700 1850) BN 3
J 2
(-1650 1860);
DISPLAY 0.617021 (-1650 1860);
PAINT PINK (-1650 1860);
FORCEPROP 2 LAST CDS_LIB mstr_standard
J 2
(-1650 1850);
DISPLAY 0.787234 (-1650 1850);
PAINT MONO (-1650 1850);
DISPLAY INVISIBLE (-1650 1850);
FORCEPROP 1 LAST BODY_TYPE PLUMBING
J 2
(-1650 1800);
DISPLAY 1.234043 (-1650 1800);
PAINT GREEN (-1650 1800);
DISPLAY INVISIBLE (-1650 1800);
FORCEPROP 1 LAST HDL_TAP TRUE
J 2
(-1975 1725);
DISPLAY 1.234043 (-1975 1725);
PAINT GREEN (-1975 1725);
DISPLAY INVISIBLE (-1975 1725);
FORCEPROP 1 LAST PATH I107
J 2
(-1650 1850);
DISPLAY 0.936170 (-1650 1850);
PAINT GREEN (-1650 1850);
DISPLAY INVISIBLE (-1650 1850);
FORCEADD TAP..6
R 2
(-1650 1750);
FORCEPROP 3 LASTPIN (-1700 1750) SIG_NAME M_C_DQ<1>
J 0
(-1690 1760);
DISPLAY 0.659574 (-1690 1760);
PAINT MONO (-1690 1760);
DISPLAY INVISIBLE (-1690 1760);
FORCEPROP 1 LASTPIN (-1700 1750) BN 1
J 2
(-1650 1760);
DISPLAY 0.617021 (-1650 1760);
PAINT PINK (-1650 1760);
FORCEPROP 2 LAST CDS_LIB mstr_standard
J 2
(-1650 1750);
DISPLAY 0.787234 (-1650 1750);
PAINT MONO (-1650 1750);
DISPLAY INVISIBLE (-1650 1750);
FORCEPROP 1 LAST BODY_TYPE PLUMBING
J 2
(-1650 1700);
DISPLAY 1.234043 (-1650 1700);
PAINT GREEN (-1650 1700);
DISPLAY INVISIBLE (-1650 1700);
FORCEPROP 1 LAST HDL_TAP TRUE
J 2
(-1975 1625);
DISPLAY 1.234043 (-1975 1625);
PAINT GREEN (-1975 1625);
DISPLAY INVISIBLE (-1975 1625);
FORCEPROP 1 LAST PATH I108
J 2
(-1650 1750);
DISPLAY 0.936170 (-1650 1750);
PAINT GREEN (-1650 1750);
DISPLAY INVISIBLE (-1650 1750);
FORCEADD TAP..6
R 2
(-1650 1800);
FORCEPROP 3 LASTPIN (-1700 1800) SIG_NAME M_C_DQ<2>
J 0
(-1690 1810);
DISPLAY 0.659574 (-1690 1810);
PAINT MONO (-1690 1810);
DISPLAY INVISIBLE (-1690 1810);
FORCEPROP 1 LASTPIN (-1700 1800) BN 2
J 2
(-1650 1810);
DISPLAY 0.617021 (-1650 1810);
PAINT PINK (-1650 1810);
FORCEPROP 2 LAST CDS_LIB mstr_standard
J 2
(-1650 1800);
DISPLAY 0.787234 (-1650 1800);
PAINT MONO (-1650 1800);
DISPLAY INVISIBLE (-1650 1800);
FORCEPROP 1 LAST BODY_TYPE PLUMBING
J 2
(-1650 1750);
DISPLAY 1.234043 (-1650 1750);
PAINT GREEN (-1650 1750);
DISPLAY INVISIBLE (-1650 1750);
FORCEPROP 1 LAST HDL_TAP TRUE
J 2
(-1975 1675);
DISPLAY 1.234043 (-1975 1675);
PAINT GREEN (-1975 1675);
DISPLAY INVISIBLE (-1975 1675);
FORCEPROP 1 LAST PATH I109
J 2
(-1650 1800);
DISPLAY 0.936170 (-1650 1800);
PAINT GREEN (-1650 1800);
DISPLAY INVISIBLE (-1650 1800);
FORCEADD TAP..6
R 2
(-1650 1700);
FORCEPROP 3 LASTPIN (-1700 1700) SIG_NAME M_C_DQ<0>
J 0
(-1690 1710);
DISPLAY 0.659574 (-1690 1710);
PAINT MONO (-1690 1710);
DISPLAY INVISIBLE (-1690 1710);
FORCEPROP 1 LASTPIN (-1700 1700) BN 0
J 2
(-1650 1710);
DISPLAY 0.617021 (-1650 1710);
PAINT PINK (-1650 1710);
FORCEPROP 2 LAST CDS_LIB mstr_standard
J 2
(-1650 1700);
DISPLAY 0.787234 (-1650 1700);
PAINT MONO (-1650 1700);
DISPLAY INVISIBLE (-1650 1700);
FORCEPROP 1 LAST BODY_TYPE PLUMBING
J 2
(-1650 1650);
DISPLAY 1.234043 (-1650 1650);
PAINT GREEN (-1650 1650);
DISPLAY INVISIBLE (-1650 1650);
FORCEPROP 1 LAST HDL_TAP TRUE
J 2
(-1975 1575);
DISPLAY 1.234043 (-1975 1575);
PAINT GREEN (-1975 1575);
DISPLAY INVISIBLE (-1975 1575);
FORCEPROP 1 LAST PATH I110
J 2
(-1650 1700);
DISPLAY 0.936170 (-1650 1700);
PAINT GREEN (-1650 1700);
DISPLAY INVISIBLE (-1650 1700);
FORCEADD SCONN288_H44441003..1
(-2400 3200);
FORCEPROP 1 LAST LOCATION J6U2
J 0
(-2850 5100);
DISPLAY 0.617021 (-2850 5100);
PAINT AQUA (-2850 5100);
FORCEPROP 1 LAST PART_NUMBER H44441-003
J 0
(-2850 1200);
DISPLAY 0.617021 (-2850 1200);
PAINT BLUE (-2850 1200);
FORCEPROP 1 LAST MATERIAL SCONN
J 0
(-2850 5050);
DISPLAY 0.617021 (-2850 5050);
PAINT SKYBLUE (-2850 5050);
FORCEPROP 2 LASTPIN (-2900 1700) $PN 146
J 2
(-2910 1710);
DISPLAY 0.617021 (-2910 1710);
PAINT ORANGE (-2910 1710);
FORCEPROP 2 LASTPIN (-2900 2050) $PN 284
J 2
(-2910 2060);
DISPLAY 0.617021 (-2910 2060);
PAINT ORANGE (-2910 2060);
FORCEPROP 2 LASTPIN (-2900 1850) $PN 285
J 2
(-2910 1860);
DISPLAY 0.617021 (-2910 1860);
PAINT ORANGE (-2910 1860);
FORCEPROP 2 LASTPIN (-2900 1800) $PN 141
J 2
(-2910 1810);
DISPLAY 0.617021 (-2910 1810);
PAINT ORANGE (-2910 1810);
FORCEPROP 2 LASTPIN (-2900 1400) $PN 230
J 2
(-2910 1410);
DISPLAY 0.617021 (-2910 1410);
PAINT ORANGE (-2910 1410);
FORCEPROP 2 LASTPIN (-2900 2000) $PN 238
J 2
(-2910 2010);
DISPLAY 0.617021 (-2910 2010);
PAINT ORANGE (-2910 2010);
FORCEPROP 2 LASTPIN (-2900 1950) $PN 140
J 2
(-2910 1960);
DISPLAY 0.617021 (-2910 1960);
PAINT ORANGE (-2910 1960);
FORCEPROP 2 LASTPIN (-2900 1900) $PN 139
J 2
(-2910 1910);
DISPLAY 0.617021 (-2910 1910);
PAINT ORANGE (-2910 1910);
FORCEPROP 2 LASTPIN (-2900 3350) $PN 237
J 2
(-2910 3360);
DISPLAY 0.617021 (-2910 3360);
PAINT ORANGE (-2910 3360);
FORCEPROP 2 LASTPIN (-2900 3300) $PN 93
J 2
(-2910 3310);
DISPLAY 0.617021 (-2910 3310);
PAINT ORANGE (-2910 3310);
FORCEPROP 2 LASTPIN (-2900 3250) $PN 89
J 2
(-2910 3260);
DISPLAY 0.617021 (-2910 3260);
PAINT ORANGE (-2910 3260);
FORCEPROP 2 LASTPIN (-2900 3200) $PN 84
J 2
(-2910 3210);
DISPLAY 0.617021 (-2910 3210);
PAINT ORANGE (-2910 3210);
FORCEPROP 2 LASTPIN (-2900 1600) $PN 144
J 2
(-2910 1610);
DISPLAY 0.617021 (-2910 1610);
PAINT ORANGE (-2910 1610);
FORCEPROP 2 LASTPIN (-2900 1550) $PN 227
J 2
(-2910 1560);
DISPLAY 0.617021 (-2910 1560);
PAINT ORANGE (-2910 1560);
FORCEPROP 2 LASTPIN (-2900 1500) $PN 205
J 2
(-2910 1510);
DISPLAY 0.617021 (-2910 1510);
PAINT ORANGE (-2910 1510);
FORCEPROP 2 LASTPIN (-2900 2300) $PN 58
J 2
(-2910 2310);
DISPLAY 0.617021 (-2910 2310);
PAINT ORANGE (-2910 2310);
FORCEPROP 2 LASTPIN (-2900 2350) $PN 222
J 2
(-2910 2360);
DISPLAY 0.617021 (-2910 2360);
PAINT ORANGE (-2910 2360);
FORCEPROP 2 LASTPIN (-2900 2950) $PN 91
J 2
(-2910 2960);
DISPLAY 0.617021 (-2910 2960);
PAINT ORANGE (-2910 2960);
FORCEPROP 2 LASTPIN (-2900 2900) $PN 87
J 2
(-2910 2910);
DISPLAY 0.617021 (-2910 2910);
PAINT ORANGE (-2910 2910);
FORCEPROP 2 LASTPIN (-2900 2250) $PN 78
J 2
(-2910 2260);
DISPLAY 0.617021 (-2910 2260);
PAINT ORANGE (-2910 2260);
FORCEPROP 2 LASTPIN (-1900 4850) $PN 280
J 0
(-1890 4860);
DISPLAY 0.617021 (-1890 4860);
PAINT ORANGE (-1890 4860);
FORCEPROP 2 LASTPIN (-1900 4800) $PN 135
J 0
(-1890 4810);
DISPLAY 0.617021 (-1890 4810);
PAINT ORANGE (-1890 4810);
FORCEPROP 2 LASTPIN (-1900 4750) $PN 273
J 0
(-1890 4760);
DISPLAY 0.617021 (-1890 4760);
PAINT ORANGE (-1890 4760);
FORCEPROP 2 LASTPIN (-1900 4700) $PN 128
J 0
(-1890 4710);
DISPLAY 0.617021 (-1890 4710);
PAINT ORANGE (-1890 4710);
FORCEPROP 2 LASTPIN (-1900 4650) $PN 282
J 0
(-1890 4660);
DISPLAY 0.617021 (-1890 4660);
PAINT ORANGE (-1890 4660);
FORCEPROP 2 LASTPIN (-1900 4600) $PN 137
J 0
(-1890 4610);
DISPLAY 0.617021 (-1890 4610);
PAINT ORANGE (-1890 4610);
FORCEPROP 2 LASTPIN (-1900 4550) $PN 275
J 0
(-1890 4560);
DISPLAY 0.617021 (-1890 4560);
PAINT ORANGE (-1890 4560);
FORCEPROP 2 LASTPIN (-1900 4500) $PN 130
J 0
(-1890 4510);
DISPLAY 0.617021 (-1890 4510);
PAINT ORANGE (-1890 4510);
FORCEPROP 2 LASTPIN (-1900 4450) $PN 269
J 0
(-1890 4460);
DISPLAY 0.617021 (-1890 4460);
PAINT ORANGE (-1890 4460);
FORCEPROP 2 LASTPIN (-1900 4400) $PN 124
J 0
(-1890 4410);
DISPLAY 0.617021 (-1890 4410);
PAINT ORANGE (-1890 4410);
FORCEPROP 2 LASTPIN (-1900 4350) $PN 262
J 0
(-1890 4360);
DISPLAY 0.617021 (-1890 4360);
PAINT ORANGE (-1890 4360);
FORCEPROP 2 LASTPIN (-1900 4300) $PN 117
J 0
(-1890 4310);
DISPLAY 0.617021 (-1890 4310);
PAINT ORANGE (-1890 4310);
FORCEPROP 2 LASTPIN (-1900 4250) $PN 271
J 0
(-1890 4260);
DISPLAY 0.617021 (-1890 4260);
PAINT ORANGE (-1890 4260);
FORCEPROP 2 LASTPIN (-1900 4200) $PN 126
J 0
(-1890 4210);
DISPLAY 0.617021 (-1890 4210);
PAINT ORANGE (-1890 4210);
FORCEPROP 2 LASTPIN (-1900 4150) $PN 264
J 0
(-1890 4160);
DISPLAY 0.617021 (-1890 4160);
PAINT ORANGE (-1890 4160);
FORCEPROP 2 LASTPIN (-1900 4100) $PN 119
J 0
(-1890 4110);
DISPLAY 0.617021 (-1890 4110);
PAINT ORANGE (-1890 4110);
FORCEPROP 2 LASTPIN (-1900 4050) $PN 258
J 0
(-1890 4060);
DISPLAY 0.617021 (-1890 4060);
PAINT ORANGE (-1890 4060);
FORCEPROP 2 LASTPIN (-1900 4000) $PN 113
J 0
(-1890 4010);
DISPLAY 0.617021 (-1890 4010);
PAINT ORANGE (-1890 4010);
FORCEPROP 2 LASTPIN (-1900 3950) $PN 251
J 0
(-1890 3960);
DISPLAY 0.617021 (-1890 3960);
PAINT ORANGE (-1890 3960);
FORCEPROP 2 LASTPIN (-1900 3900) $PN 106
J 0
(-1890 3910);
DISPLAY 0.617021 (-1890 3910);
PAINT ORANGE (-1890 3910);
FORCEPROP 2 LASTPIN (-1900 3850) $PN 260
J 0
(-1890 3860);
DISPLAY 0.617021 (-1890 3860);
PAINT ORANGE (-1890 3860);
FORCEPROP 2 LASTPIN (-1900 3800) $PN 115
J 0
(-1890 3810);
DISPLAY 0.617021 (-1890 3810);
PAINT ORANGE (-1890 3810);
FORCEPROP 2 LASTPIN (-1900 3750) $PN 253
J 0
(-1890 3760);
DISPLAY 0.617021 (-1890 3760);
PAINT ORANGE (-1890 3760);
FORCEPROP 2 LASTPIN (-1900 3700) $PN 108
J 0
(-1890 3710);
DISPLAY 0.617021 (-1890 3710);
PAINT ORANGE (-1890 3710);
FORCEPROP 2 LASTPIN (-1900 3650) $PN 247
J 0
(-1890 3660);
DISPLAY 0.617021 (-1890 3660);
PAINT ORANGE (-1890 3660);
FORCEPROP 2 LASTPIN (-1900 3600) $PN 102
J 0
(-1890 3610);
DISPLAY 0.617021 (-1890 3610);
PAINT ORANGE (-1890 3610);
FORCEPROP 2 LASTPIN (-1900 3550) $PN 240
J 0
(-1890 3560);
DISPLAY 0.617021 (-1890 3560);
PAINT ORANGE (-1890 3560);
FORCEPROP 2 LASTPIN (-1900 3500) $PN 95
J 0
(-1890 3510);
DISPLAY 0.617021 (-1890 3510);
PAINT ORANGE (-1890 3510);
FORCEPROP 2 LASTPIN (-1900 3450) $PN 249
J 0
(-1890 3460);
DISPLAY 0.617021 (-1890 3460);
PAINT ORANGE (-1890 3460);
FORCEPROP 2 LASTPIN (-1900 3400) $PN 104
J 0
(-1890 3410);
DISPLAY 0.617021 (-1890 3410);
PAINT ORANGE (-1890 3410);
FORCEPROP 2 LASTPIN (-1900 3350) $PN 242
J 0
(-1890 3360);
DISPLAY 0.617021 (-1890 3360);
PAINT ORANGE (-1890 3360);
FORCEPROP 2 LASTPIN (-1900 3300) $PN 97
J 0
(-1890 3310);
DISPLAY 0.617021 (-1890 3310);
PAINT ORANGE (-1890 3310);
FORCEPROP 2 LASTPIN (-1900 3250) $PN 188
J 0
(-1890 3260);
DISPLAY 0.617021 (-1890 3260);
PAINT ORANGE (-1890 3260);
FORCEPROP 2 LASTPIN (-1900 3200) $PN 43
J 0
(-1890 3210);
DISPLAY 0.617021 (-1890 3210);
PAINT ORANGE (-1890 3210);
FORCEPROP 2 LASTPIN (-1900 3150) $PN 181
J 0
(-1890 3160);
DISPLAY 0.617021 (-1890 3160);
PAINT ORANGE (-1890 3160);
FORCEPROP 2 LASTPIN (-1900 3100) $PN 36
J 0
(-1890 3110);
DISPLAY 0.617021 (-1890 3110);
PAINT ORANGE (-1890 3110);
FORCEPROP 2 LASTPIN (-1900 3050) $PN 190
J 0
(-1890 3060);
DISPLAY 0.617021 (-1890 3060);
PAINT ORANGE (-1890 3060);
FORCEPROP 2 LASTPIN (-1900 3000) $PN 45
J 0
(-1890 3010);
DISPLAY 0.617021 (-1890 3010);
PAINT ORANGE (-1890 3010);
FORCEPROP 2 LASTPIN (-1900 2950) $PN 183
J 0
(-1890 2960);
DISPLAY 0.617021 (-1890 2960);
PAINT ORANGE (-1890 2960);
FORCEPROP 2 LASTPIN (-1900 2900) $PN 38
J 0
(-1890 2910);
DISPLAY 0.617021 (-1890 2910);
PAINT ORANGE (-1890 2910);
FORCEPROP 2 LASTPIN (-1900 2850) $PN 177
J 0
(-1890 2860);
DISPLAY 0.617021 (-1890 2860);
PAINT ORANGE (-1890 2860);
FORCEPROP 2 LASTPIN (-1900 2800) $PN 32
J 0
(-1890 2810);
DISPLAY 0.617021 (-1890 2810);
PAINT ORANGE (-1890 2810);
FORCEPROP 2 LASTPIN (-1900 2750) $PN 170
J 0
(-1890 2760);
DISPLAY 0.617021 (-1890 2760);
PAINT ORANGE (-1890 2760);
FORCEPROP 2 LASTPIN (-1900 2700) $PN 25
J 0
(-1890 2710);
DISPLAY 0.617021 (-1890 2710);
PAINT ORANGE (-1890 2710);
FORCEPROP 2 LASTPIN (-1900 2650) $PN 179
J 0
(-1890 2660);
DISPLAY 0.617021 (-1890 2660);
PAINT ORANGE (-1890 2660);
FORCEPROP 2 LASTPIN (-1900 2600) $PN 34
J 0
(-1890 2610);
DISPLAY 0.617021 (-1890 2610);
PAINT ORANGE (-1890 2610);
FORCEPROP 2 LASTPIN (-1900 2550) $PN 172
J 0
(-1890 2560);
DISPLAY 0.617021 (-1890 2560);
PAINT ORANGE (-1890 2560);
FORCEPROP 2 LASTPIN (-1900 2500) $PN 27
J 0
(-1890 2510);
DISPLAY 0.617021 (-1890 2510);
PAINT ORANGE (-1890 2510);
FORCEPROP 2 LASTPIN (-1900 2450) $PN 166
J 0
(-1890 2460);
DISPLAY 0.617021 (-1890 2460);
PAINT ORANGE (-1890 2460);
FORCEPROP 2 LASTPIN (-1900 2400) $PN 21
J 0
(-1890 2410);
DISPLAY 0.617021 (-1890 2410);
PAINT ORANGE (-1890 2410);
FORCEPROP 2 LASTPIN (-1900 2350) $PN 159
J 0
(-1890 2360);
DISPLAY 0.617021 (-1890 2360);
PAINT ORANGE (-1890 2360);
FORCEPROP 2 LASTPIN (-1900 2300) $PN 14
J 0
(-1890 2310);
DISPLAY 0.617021 (-1890 2310);
PAINT ORANGE (-1890 2310);
FORCEPROP 2 LASTPIN (-1900 2250) $PN 168
J 0
(-1890 2260);
DISPLAY 0.617021 (-1890 2260);
PAINT ORANGE (-1890 2260);
FORCEPROP 2 LASTPIN (-1900 2200) $PN 23
J 0
(-1890 2210);
DISPLAY 0.617021 (-1890 2210);
PAINT ORANGE (-1890 2210);
FORCEPROP 2 LASTPIN (-1900 2150) $PN 161
J 0
(-1890 2160);
DISPLAY 0.617021 (-1890 2160);
PAINT ORANGE (-1890 2160);
FORCEPROP 2 LASTPIN (-1900 2100) $PN 16
J 0
(-1890 2110);
DISPLAY 0.617021 (-1890 2110);
PAINT ORANGE (-1890 2110);
FORCEPROP 2 LASTPIN (-1900 2050) $PN 155
J 0
(-1890 2060);
DISPLAY 0.617021 (-1890 2060);
PAINT ORANGE (-1890 2060);
FORCEPROP 2 LASTPIN (-1900 2000) $PN 10
J 0
(-1890 2010);
DISPLAY 0.617021 (-1890 2010);
PAINT ORANGE (-1890 2010);
FORCEPROP 2 LASTPIN (-1900 1950) $PN 148
J 0
(-1890 1960);
DISPLAY 0.617021 (-1890 1960);
PAINT ORANGE (-1890 1960);
FORCEPROP 2 LASTPIN (-1900 1900) $PN 3
J 0
(-1890 1910);
DISPLAY 0.617021 (-1890 1910);
PAINT ORANGE (-1890 1910);
FORCEPROP 2 LASTPIN (-1900 1850) $PN 157
J 0
(-1890 1860);
DISPLAY 0.617021 (-1890 1860);
PAINT ORANGE (-1890 1860);
FORCEPROP 2 LASTPIN (-1900 1800) $PN 12
J 0
(-1890 1810);
DISPLAY 0.617021 (-1890 1810);
PAINT ORANGE (-1890 1810);
FORCEPROP 2 LASTPIN (-1900 1750) $PN 150
J 0
(-1890 1760);
DISPLAY 0.617021 (-1890 1760);
PAINT ORANGE (-1890 1760);
FORCEPROP 2 LASTPIN (-1900 1700) $PN 5
J 0
(-1890 1710);
DISPLAY 0.617021 (-1890 1710);
PAINT ORANGE (-1890 1710);
FORCEPROP 2 LASTPIN (-2900 3100) $PN 203
J 2
(-2910 3110);
DISPLAY 0.617021 (-2910 3110);
PAINT ORANGE (-2910 3110);
FORCEPROP 2 LASTPIN (-2900 3050) $PN 60
J 2
(-2910 3060);
DISPLAY 0.617021 (-2910 3060);
PAINT ORANGE (-2910 3060);
FORCEPROP 2 LASTPIN (-2900 3650) $PN 218
J 2
(-2910 3660);
DISPLAY 0.617021 (-2910 3660);
PAINT ORANGE (-2910 3660);
FORCEPROP 2 LASTPIN (-2900 3600) $PN 219
J 2
(-2910 3610);
DISPLAY 0.617021 (-2910 3610);
PAINT ORANGE (-2910 3610);
FORCEPROP 2 LASTPIN (-2900 3550) $PN 74
J 2
(-2910 3560);
DISPLAY 0.617021 (-2910 3560);
PAINT ORANGE (-2910 3560);
FORCEPROP 2 LASTPIN (-2900 3500) $PN 75
J 2
(-2910 3510);
DISPLAY 0.617021 (-2910 3510);
PAINT ORANGE (-2910 3510);
FORCEPROP 2 LASTPIN (-2900 2800) $PN 199
J 2
(-2910 2810);
DISPLAY 0.617021 (-2910 2810);
PAINT ORANGE (-2910 2810);
FORCEPROP 2 LASTPIN (-2900 2750) $PN 54
J 2
(-2910 2760);
DISPLAY 0.617021 (-2910 2760);
PAINT ORANGE (-2910 2760);
FORCEPROP 2 LASTPIN (-2900 2700) $PN 192
J 2
(-2910 2710);
DISPLAY 0.617021 (-2910 2710);
PAINT ORANGE (-2910 2710);
FORCEPROP 2 LASTPIN (-2900 2650) $PN 47
J 2
(-2910 2660);
DISPLAY 0.617021 (-2910 2660);
PAINT ORANGE (-2910 2660);
FORCEPROP 2 LASTPIN (-2900 2600) $PN 201
J 2
(-2910 2610);
DISPLAY 0.617021 (-2910 2610);
PAINT ORANGE (-2910 2610);
FORCEPROP 2 LASTPIN (-2900 2550) $PN 56
J 2
(-2910 2560);
DISPLAY 0.617021 (-2910 2560);
PAINT ORANGE (-2910 2560);
FORCEPROP 2 LASTPIN (-2900 2500) $PN 194
J 2
(-2910 2510);
DISPLAY 0.617021 (-2910 2510);
PAINT ORANGE (-2910 2510);
FORCEPROP 2 LASTPIN (-2900 2450) $PN 49
J 2
(-2910 2460);
DISPLAY 0.617021 (-2910 2460);
PAINT ORANGE (-2910 2460);
FORCEPROP 2 LASTPIN (-2900 3400) $PN 235
J 2
(-2910 3410);
DISPLAY 0.617021 (-2910 3410);
PAINT ORANGE (-2910 3410);
FORCEPROP 2 LASTPIN (-2900 3800) $PN 207
J 2
(-2910 3810);
DISPLAY 0.617021 (-2910 3810);
PAINT ORANGE (-2910 3810);
FORCEPROP 2 LASTPIN (-2900 3750) $PN 63
J 2
(-2910 3760);
DISPLAY 0.617021 (-2910 3760);
PAINT ORANGE (-2910 3760);
FORCEPROP 2 LASTPIN (-2900 3900) $PN 224
J 2
(-2910 3910);
DISPLAY 0.617021 (-2910 3910);
PAINT ORANGE (-2910 3910);
FORCEPROP 2 LASTPIN (-2900 3850) $PN 81
J 2
(-2910 3860);
DISPLAY 0.617021 (-2910 3860);
PAINT ORANGE (-2910 3860);
FORCEPROP 2 LASTPIN (-2900 2200) $PN 208
J 2
(-2910 2210);
DISPLAY 0.617021 (-2910 2210);
PAINT ORANGE (-2910 2210);
FORCEPROP 2 LASTPIN (-2900 2150) $PN 62
J 2
(-2910 2160);
DISPLAY 0.617021 (-2910 2160);
PAINT ORANGE (-2910 2160);
FORCEPROP 2 LASTPIN (-2900 4850) $PN 234
J 2
(-2910 4860);
DISPLAY 0.617021 (-2910 4860);
PAINT ORANGE (-2910 4860);
FORCEPROP 2 LASTPIN (-2900 4800) $PN 82
J 2
(-2910 4810);
DISPLAY 0.617021 (-2910 4810);
PAINT ORANGE (-2910 4810);
FORCEPROP 2 LASTPIN (-2900 4750) $PN 86
J 2
(-2910 4760);
DISPLAY 0.617021 (-2910 4760);
PAINT ORANGE (-2910 4760);
FORCEPROP 2 LASTPIN (-2900 4700) $PN 228
J 2
(-2910 4710);
DISPLAY 0.617021 (-2910 4710);
PAINT ORANGE (-2910 4710);
FORCEPROP 2 LASTPIN (-2900 4650) $PN 232
J 2
(-2910 4660);
DISPLAY 0.617021 (-2910 4660);
PAINT ORANGE (-2910 4660);
FORCEPROP 2 LASTPIN (-2900 4600) $PN 65
J 2
(-2910 4610);
DISPLAY 0.617021 (-2910 4610);
PAINT ORANGE (-2910 4610);
FORCEPROP 2 LASTPIN (-2900 4550) $PN 210
J 2
(-2910 4560);
DISPLAY 0.617021 (-2910 4560);
PAINT ORANGE (-2910 4560);
FORCEPROP 2 LASTPIN (-2900 4500) $PN 225
J 2
(-2910 4510);
DISPLAY 0.617021 (-2910 4510);
PAINT ORANGE (-2910 4510);
FORCEPROP 2 LASTPIN (-2900 4450) $PN 66
J 2
(-2910 4460);
DISPLAY 0.617021 (-2910 4460);
PAINT ORANGE (-2910 4460);
FORCEPROP 2 LASTPIN (-2900 4400) $PN 68
J 2
(-2910 4410);
DISPLAY 0.617021 (-2910 4410);
PAINT ORANGE (-2910 4410);
FORCEPROP 2 LASTPIN (-2900 4350) $PN 211
J 2
(-2910 4360);
DISPLAY 0.617021 (-2910 4360);
PAINT ORANGE (-2910 4360);
FORCEPROP 2 LASTPIN (-2900 4300) $PN 69
J 2
(-2910 4310);
DISPLAY 0.617021 (-2910 4310);
PAINT ORANGE (-2910 4310);
FORCEPROP 2 LASTPIN (-2900 4250) $PN 213
J 2
(-2910 4260);
DISPLAY 0.617021 (-2910 4260);
PAINT ORANGE (-2910 4260);
FORCEPROP 2 LASTPIN (-2900 4200) $PN 214
J 2
(-2910 4210);
DISPLAY 0.617021 (-2910 4210);
PAINT ORANGE (-2910 4210);
FORCEPROP 2 LASTPIN (-2900 4150) $PN 71
J 2
(-2910 4160);
DISPLAY 0.617021 (-2910 4160);
PAINT ORANGE (-2910 4160);
FORCEPROP 2 LASTPIN (-2900 4100) $PN 216
J 2
(-2910 4110);
DISPLAY 0.617021 (-2910 4110);
PAINT ORANGE (-2910 4110);
FORCEPROP 2 LASTPIN (-2900 4050) $PN 72
J 2
(-2910 4060);
DISPLAY 0.617021 (-2910 4060);
PAINT ORANGE (-2910 4060);
FORCEPROP 2 LASTPIN (-2900 4000) $PN 79
J 2
(-2910 4010);
DISPLAY 0.617021 (-2910 4010);
PAINT ORANGE (-2910 4010);
FORCEPROP 1 LAST PACK_TYPE PIP
J 0
(-2850 5150);
PAINT SKYBLUE (-2850 5150);
DISPLAY INVISIBLE (-2850 5150);
FORCEPROP 2 LAST BOM_COST MEM
J 0
(-2400 3200);
PAINT ORANGE (-2400 3200);
DISPLAY INVISIBLE (-2400 3200);
FORCEPROP 2 LAST CDS_LIB mstr_sconn
J 0
(-2400 3200);
PAINT ORANGE (-2400 3200);
DISPLAY INVISIBLE (-2400 3200);
FORCEPROP 2 LAST SEC_TYPE PIP
J 0
(-2850 5150);
DISPLAY 1.021277 (-2850 5150);
PAINT ORANGE (-2850 5150);
DISPLAY INVISIBLE (-2850 5150);
FORCEPROP 2 LAST SEC 1
J 0
(-2850 5150);
DISPLAY 0.680851 (-2850 5150);
PAINT MONO (-2850 5150);
DISPLAY INVISIBLE (-2850 5150);
FORCEPROP 2 LAST CDS_LOCATION J6U2
J 0
(-2850 5100);
DISPLAY 0.617021 (-2850 5100);
PAINT AQUA (-2850 5100);
DISPLAY INVISIBLE (-2850 5100);
FORCEPROP 1 LAST PATH I111
J 0
(-2400 5050);
PAINT GREEN (-2400 5050);
DISPLAY INVISIBLE (-2400 5050);
FORCEPROP 2 LAST ROOM DDR4_CH_C1
J 0
(-2400 3200);
PAINT ORANGE (-2400 3200);
DISPLAY INVISIBLE (-2400 3200);
FORCEADD TAP..6
(-3150 4850);
FORCEPROP 3 LASTPIN (-3100 4850) SIG_NAME M_C_MA<17>
J 0
(-3090 4860);
DISPLAY 0.659574 (-3090 4860);
PAINT MONO (-3090 4860);
DISPLAY INVISIBLE (-3090 4860);
FORCEPROP 1 LASTPIN (-3100 4850) BN 17
J 0
(-3150 4860);
DISPLAY 0.617021 (-3150 4860);
PAINT PINK (-3150 4860);
FORCEPROP 2 LAST CDS_LIB mstr_standard
J 0
(-3150 4850);
DISPLAY 0.787234 (-3150 4850);
PAINT MONO (-3150 4850);
DISPLAY INVISIBLE (-3150 4850);
FORCEPROP 1 LAST BODY_TYPE PLUMBING
J 0
(-3150 4800);
DISPLAY 1.234043 (-3150 4800);
PAINT GREEN (-3150 4800);
DISPLAY INVISIBLE (-3150 4800);
FORCEPROP 1 LAST HDL_TAP TRUE
J 0
(-2825 4725);
DISPLAY 1.234043 (-2825 4725);
PAINT GREEN (-2825 4725);
DISPLAY INVISIBLE (-2825 4725);
FORCEPROP 1 LAST PATH I112
J 0
(-3150 4850);
DISPLAY 0.936170 (-3150 4850);
PAINT GREEN (-3150 4850);
DISPLAY INVISIBLE (-3150 4850);
FORCEADD TAP..6
(-3150 4800);
FORCEPROP 3 LASTPIN (-3100 4800) SIG_NAME M_C_MA<16>
J 0
(-3090 4810);
DISPLAY 0.659574 (-3090 4810);
PAINT MONO (-3090 4810);
DISPLAY INVISIBLE (-3090 4810);
FORCEPROP 1 LASTPIN (-3100 4800) BN 16
J 0
(-3150 4810);
DISPLAY 0.617021 (-3150 4810);
PAINT PINK (-3150 4810);
FORCEPROP 2 LAST CDS_LIB mstr_standard
J 2
(-3150 4800);
DISPLAY 0.787234 (-3150 4800);
PAINT MONO (-3150 4800);
DISPLAY INVISIBLE (-3150 4800);
FORCEPROP 1 LAST BODY_TYPE PLUMBING
J 0
(-3150 4750);
DISPLAY 1.234043 (-3150 4750);
PAINT GREEN (-3150 4750);
DISPLAY INVISIBLE (-3150 4750);
FORCEPROP 1 LAST HDL_TAP TRUE
J 0
(-2825 4675);
DISPLAY 1.234043 (-2825 4675);
PAINT GREEN (-2825 4675);
DISPLAY INVISIBLE (-2825 4675);
FORCEPROP 1 LAST PATH I113
J 0
(-3150 4800);
DISPLAY 0.936170 (-3150 4800);
PAINT GREEN (-3150 4800);
DISPLAY INVISIBLE (-3150 4800);
FORCEADD TAP..6
(-3150 4750);
FORCEPROP 3 LASTPIN (-3100 4750) SIG_NAME M_C_MA<15>
J 0
(-3090 4760);
DISPLAY 0.659574 (-3090 4760);
PAINT MONO (-3090 4760);
DISPLAY INVISIBLE (-3090 4760);
FORCEPROP 1 LASTPIN (-3100 4750) BN 15
J 0
(-3150 4760);
DISPLAY 0.617021 (-3150 4760);
PAINT PINK (-3150 4760);
FORCEPROP 2 LAST CDS_LIB mstr_standard
J 2
(-3150 4750);
DISPLAY 0.787234 (-3150 4750);
PAINT MONO (-3150 4750);
DISPLAY INVISIBLE (-3150 4750);
FORCEPROP 1 LAST BODY_TYPE PLUMBING
J 0
(-3150 4700);
DISPLAY 1.234043 (-3150 4700);
PAINT GREEN (-3150 4700);
DISPLAY INVISIBLE (-3150 4700);
FORCEPROP 1 LAST HDL_TAP TRUE
J 0
(-2825 4625);
DISPLAY 1.234043 (-2825 4625);
PAINT GREEN (-2825 4625);
DISPLAY INVISIBLE (-2825 4625);
FORCEPROP 1 LAST PATH I114
J 0
(-3150 4750);
DISPLAY 0.936170 (-3150 4750);
PAINT GREEN (-3150 4750);
DISPLAY INVISIBLE (-3150 4750);
FORCEADD TAP..6
(-3150 4700);
FORCEPROP 3 LASTPIN (-3100 4700) SIG_NAME M_C_MA<14>
J 0
(-3090 4710);
DISPLAY 0.659574 (-3090 4710);
PAINT MONO (-3090 4710);
DISPLAY INVISIBLE (-3090 4710);
FORCEPROP 1 LASTPIN (-3100 4700) BN 14
J 0
(-3150 4710);
DISPLAY 0.617021 (-3150 4710);
PAINT PINK (-3150 4710);
FORCEPROP 2 LAST CDS_LIB mstr_standard
J 2
(-3150 4700);
DISPLAY 0.787234 (-3150 4700);
PAINT MONO (-3150 4700);
DISPLAY INVISIBLE (-3150 4700);
FORCEPROP 1 LAST BODY_TYPE PLUMBING
J 0
(-3150 4650);
DISPLAY 1.234043 (-3150 4650);
PAINT GREEN (-3150 4650);
DISPLAY INVISIBLE (-3150 4650);
FORCEPROP 1 LAST HDL_TAP TRUE
J 0
(-2825 4575);
DISPLAY 1.234043 (-2825 4575);
PAINT GREEN (-2825 4575);
DISPLAY INVISIBLE (-2825 4575);
FORCEPROP 1 LAST PATH I115
J 0
(-3150 4700);
DISPLAY 0.936170 (-3150 4700);
PAINT GREEN (-3150 4700);
DISPLAY INVISIBLE (-3150 4700);
FORCEADD TAP..6
(-3150 4650);
FORCEPROP 3 LASTPIN (-3100 4650) SIG_NAME M_C_MA<13>
J 0
(-3090 4660);
DISPLAY 0.659574 (-3090 4660);
PAINT MONO (-3090 4660);
DISPLAY INVISIBLE (-3090 4660);
FORCEPROP 1 LASTPIN (-3100 4650) BN 13
J 0
(-3150 4660);
DISPLAY 0.617021 (-3150 4660);
PAINT PINK (-3150 4660);
FORCEPROP 2 LAST CDS_LIB mstr_standard
J 2
(-3150 4650);
DISPLAY 0.787234 (-3150 4650);
PAINT MONO (-3150 4650);
DISPLAY INVISIBLE (-3150 4650);
FORCEPROP 1 LAST BODY_TYPE PLUMBING
J 0
(-3150 4600);
DISPLAY 1.234043 (-3150 4600);
PAINT GREEN (-3150 4600);
DISPLAY INVISIBLE (-3150 4600);
FORCEPROP 1 LAST HDL_TAP TRUE
J 0
(-2825 4525);
DISPLAY 1.234043 (-2825 4525);
PAINT GREEN (-2825 4525);
DISPLAY INVISIBLE (-2825 4525);
FORCEPROP 1 LAST PATH I116
J 0
(-3150 4650);
DISPLAY 0.936170 (-3150 4650);
PAINT GREEN (-3150 4650);
DISPLAY INVISIBLE (-3150 4650);
FORCEADD TAP..6
(-3150 4600);
FORCEPROP 3 LASTPIN (-3100 4600) SIG_NAME M_C_MA<12>
J 0
(-3090 4610);
DISPLAY 0.659574 (-3090 4610);
PAINT MONO (-3090 4610);
DISPLAY INVISIBLE (-3090 4610);
FORCEPROP 1 LASTPIN (-3100 4600) BN 12
J 0
(-3150 4610);
DISPLAY 0.617021 (-3150 4610);
PAINT PINK (-3150 4610);
FORCEPROP 2 LAST CDS_LIB mstr_standard
J 2
(-3150 4600);
DISPLAY 0.787234 (-3150 4600);
PAINT MONO (-3150 4600);
DISPLAY INVISIBLE (-3150 4600);
FORCEPROP 1 LAST BODY_TYPE PLUMBING
J 0
(-3150 4550);
DISPLAY 1.234043 (-3150 4550);
PAINT GREEN (-3150 4550);
DISPLAY INVISIBLE (-3150 4550);
FORCEPROP 1 LAST HDL_TAP TRUE
J 0
(-2825 4475);
DISPLAY 1.234043 (-2825 4475);
PAINT GREEN (-2825 4475);
DISPLAY INVISIBLE (-2825 4475);
FORCEPROP 1 LAST PATH I117
J 0
(-3150 4600);
DISPLAY 0.936170 (-3150 4600);
PAINT GREEN (-3150 4600);
DISPLAY INVISIBLE (-3150 4600);
FORCEADD TAP..6
(-3150 4550);
FORCEPROP 3 LASTPIN (-3100 4550) SIG_NAME M_C_MA<11>
J 0
(-3090 4560);
DISPLAY 0.659574 (-3090 4560);
PAINT MONO (-3090 4560);
DISPLAY INVISIBLE (-3090 4560);
FORCEPROP 1 LASTPIN (-3100 4550) BN 11
J 0
(-3150 4560);
DISPLAY 0.617021 (-3150 4560);
PAINT PINK (-3150 4560);
FORCEPROP 2 LAST CDS_LIB mstr_standard
J 2
(-3150 4550);
DISPLAY 0.787234 (-3150 4550);
PAINT MONO (-3150 4550);
DISPLAY INVISIBLE (-3150 4550);
FORCEPROP 1 LAST BODY_TYPE PLUMBING
J 0
(-3150 4500);
DISPLAY 1.234043 (-3150 4500);
PAINT GREEN (-3150 4500);
DISPLAY INVISIBLE (-3150 4500);
FORCEPROP 1 LAST HDL_TAP TRUE
J 0
(-2825 4425);
DISPLAY 1.234043 (-2825 4425);
PAINT GREEN (-2825 4425);
DISPLAY INVISIBLE (-2825 4425);
FORCEPROP 1 LAST PATH I118
J 0
(-3150 4550);
DISPLAY 0.936170 (-3150 4550);
PAINT GREEN (-3150 4550);
DISPLAY INVISIBLE (-3150 4550);
FORCEADD TAP..6
(-3150 4500);
FORCEPROP 3 LASTPIN (-3100 4500) SIG_NAME M_C_MA<10>
J 0
(-3090 4510);
DISPLAY 0.659574 (-3090 4510);
PAINT MONO (-3090 4510);
DISPLAY INVISIBLE (-3090 4510);
FORCEPROP 1 LASTPIN (-3100 4500) BN 10
J 0
(-3150 4510);
DISPLAY 0.617021 (-3150 4510);
PAINT PINK (-3150 4510);
FORCEPROP 2 LAST CDS_LIB mstr_standard
J 2
(-3150 4500);
DISPLAY 0.787234 (-3150 4500);
PAINT MONO (-3150 4500);
DISPLAY INVISIBLE (-3150 4500);
FORCEPROP 1 LAST BODY_TYPE PLUMBING
J 0
(-3150 4450);
DISPLAY 1.234043 (-3150 4450);
PAINT GREEN (-3150 4450);
DISPLAY INVISIBLE (-3150 4450);
FORCEPROP 1 LAST HDL_TAP TRUE
J 0
(-2825 4375);
DISPLAY 1.234043 (-2825 4375);
PAINT GREEN (-2825 4375);
DISPLAY INVISIBLE (-2825 4375);
FORCEPROP 1 LAST PATH I119
J 0
(-3150 4500);
DISPLAY 0.936170 (-3150 4500);
PAINT GREEN (-3150 4500);
DISPLAY INVISIBLE (-3150 4500);
FORCEADD PVTT_ABC..1
(-950 2700);
FORCEPROP 3 LASTPIN (-950 2650) SIG_NAME PVTT_ABC\g
J 0
(-940 2660);
DISPLAY 0.659574 (-940 2660);
PAINT MONO (-940 2660);
DISPLAY INVISIBLE (-940 2660);
FORCEPROP 1 LAST VOLTAGE 0.6V
J 0
(-995 2657);
DISPLAY 0.340426 (-995 2657);
PAINT SKYBLUE (-995 2657);
DISPLAY INVISIBLE (-995 2657);
FORCEPROP 2 LAST BOM_COST MEM
J 0
(-950 2705);
PAINT ORANGE (-950 2705);
DISPLAY INVISIBLE (-950 2705);
FORCEPROP 2 LAST CDS_LIB mstr_symbols
J 0
(-950 2700);
PAINT ORANGE (-950 2700);
DISPLAY INVISIBLE (-950 2700);
FORCEPROP 1 LAST BODY_TYPE PLUMBING
J 0
(-995 2657);
DISPLAY 0.340426 (-995 2657);
PAINT GREEN (-995 2657);
DISPLAY INVISIBLE (-995 2657);
FORCEPROP 1 LAST PATH I12
J 0
(-900 2725);
DISPLAY 0.872340 (-900 2725);
PAINT AQUA (-900 2725);
DISPLAY INVISIBLE (-900 2725);
FORCEPROP 2 LAST ROOM DDR4_CH_B
J 0
(-950 2705);
PAINT ORANGE (-950 2705);
DISPLAY INVISIBLE (-950 2705);
FORCEPROP 1 LAST HDL_POWER PVTT_ABC
J 1
(-950 2750);
DISPLAY 0.872340 (-950 2750);
PAINT GREEN (-950 2750);
DISPLAY INVISIBLE (-950 2750);
FORCEADD TAP..6
(-3150 4450);
FORCEPROP 3 LASTPIN (-3100 4450) SIG_NAME M_C_MA<9>
J 0
(-3090 4460);
DISPLAY 0.659574 (-3090 4460);
PAINT MONO (-3090 4460);
DISPLAY INVISIBLE (-3090 4460);
FORCEPROP 1 LASTPIN (-3100 4450) BN 9
J 0
(-3150 4460);
DISPLAY 0.617021 (-3150 4460);
PAINT PINK (-3150 4460);
FORCEPROP 2 LAST CDS_LIB mstr_standard
J 2
(-3150 4450);
DISPLAY 0.787234 (-3150 4450);
PAINT MONO (-3150 4450);
DISPLAY INVISIBLE (-3150 4450);
FORCEPROP 1 LAST BODY_TYPE PLUMBING
J 0
(-3150 4400);
DISPLAY 1.234043 (-3150 4400);
PAINT GREEN (-3150 4400);
DISPLAY INVISIBLE (-3150 4400);
FORCEPROP 1 LAST HDL_TAP TRUE
J 0
(-2825 4325);
DISPLAY 1.234043 (-2825 4325);
PAINT GREEN (-2825 4325);
DISPLAY INVISIBLE (-2825 4325);
FORCEPROP 1 LAST PATH I120
J 0
(-3150 4450);
DISPLAY 0.936170 (-3150 4450);
PAINT GREEN (-3150 4450);
DISPLAY INVISIBLE (-3150 4450);
FORCEADD TAP..6
(-3150 4400);
FORCEPROP 3 LASTPIN (-3100 4400) SIG_NAME M_C_MA<8>
J 0
(-3090 4410);
DISPLAY 0.659574 (-3090 4410);
PAINT MONO (-3090 4410);
DISPLAY INVISIBLE (-3090 4410);
FORCEPROP 1 LASTPIN (-3100 4400) BN 8
J 0
(-3150 4410);
DISPLAY 0.617021 (-3150 4410);
PAINT PINK (-3150 4410);
FORCEPROP 2 LAST CDS_LIB mstr_standard
J 2
(-3150 4400);
DISPLAY 0.787234 (-3150 4400);
PAINT MONO (-3150 4400);
DISPLAY INVISIBLE (-3150 4400);
FORCEPROP 1 LAST BODY_TYPE PLUMBING
J 0
(-3150 4350);
DISPLAY 1.234043 (-3150 4350);
PAINT GREEN (-3150 4350);
DISPLAY INVISIBLE (-3150 4350);
FORCEPROP 1 LAST HDL_TAP TRUE
J 0
(-2825 4275);
DISPLAY 1.234043 (-2825 4275);
PAINT GREEN (-2825 4275);
DISPLAY INVISIBLE (-2825 4275);
FORCEPROP 1 LAST PATH I121
J 0
(-3150 4400);
DISPLAY 0.936170 (-3150 4400);
PAINT GREEN (-3150 4400);
DISPLAY INVISIBLE (-3150 4400);
FORCEADD TAP..6
(-3150 4350);
FORCEPROP 3 LASTPIN (-3100 4350) SIG_NAME M_C_MA<7>
J 0
(-3090 4360);
DISPLAY 0.659574 (-3090 4360);
PAINT MONO (-3090 4360);
DISPLAY INVISIBLE (-3090 4360);
FORCEPROP 1 LASTPIN (-3100 4350) BN 7
J 0
(-3150 4360);
DISPLAY 0.617021 (-3150 4360);
PAINT PINK (-3150 4360);
FORCEPROP 2 LAST CDS_LIB mstr_standard
J 2
(-3150 4350);
DISPLAY 0.787234 (-3150 4350);
PAINT MONO (-3150 4350);
DISPLAY INVISIBLE (-3150 4350);
FORCEPROP 1 LAST BODY_TYPE PLUMBING
J 0
(-3150 4300);
DISPLAY 1.234043 (-3150 4300);
PAINT GREEN (-3150 4300);
DISPLAY INVISIBLE (-3150 4300);
FORCEPROP 1 LAST HDL_TAP TRUE
J 0
(-2825 4225);
DISPLAY 1.234043 (-2825 4225);
PAINT GREEN (-2825 4225);
DISPLAY INVISIBLE (-2825 4225);
FORCEPROP 1 LAST PATH I122
J 0
(-3150 4350);
DISPLAY 0.936170 (-3150 4350);
PAINT GREEN (-3150 4350);
DISPLAY INVISIBLE (-3150 4350);
FORCEADD TAP..6
(-3150 4300);
FORCEPROP 3 LASTPIN (-3100 4300) SIG_NAME M_C_MA<6>
J 0
(-3090 4310);
DISPLAY 0.659574 (-3090 4310);
PAINT MONO (-3090 4310);
DISPLAY INVISIBLE (-3090 4310);
FORCEPROP 1 LASTPIN (-3100 4300) BN 6
J 0
(-3150 4310);
DISPLAY 0.617021 (-3150 4310);
PAINT PINK (-3150 4310);
FORCEPROP 2 LAST CDS_LIB mstr_standard
J 2
(-3150 4300);
DISPLAY 0.787234 (-3150 4300);
PAINT MONO (-3150 4300);
DISPLAY INVISIBLE (-3150 4300);
FORCEPROP 1 LAST BODY_TYPE PLUMBING
J 0
(-3150 4250);
DISPLAY 1.234043 (-3150 4250);
PAINT GREEN (-3150 4250);
DISPLAY INVISIBLE (-3150 4250);
FORCEPROP 1 LAST HDL_TAP TRUE
J 0
(-2825 4175);
DISPLAY 1.234043 (-2825 4175);
PAINT GREEN (-2825 4175);
DISPLAY INVISIBLE (-2825 4175);
FORCEPROP 1 LAST PATH I123
J 0
(-3150 4300);
DISPLAY 0.936170 (-3150 4300);
PAINT GREEN (-3150 4300);
DISPLAY INVISIBLE (-3150 4300);
FORCEADD TAP..6
(-3150 4250);
FORCEPROP 3 LASTPIN (-3100 4250) SIG_NAME M_C_MA<5>
J 0
(-3090 4260);
DISPLAY 0.659574 (-3090 4260);
PAINT MONO (-3090 4260);
DISPLAY INVISIBLE (-3090 4260);
FORCEPROP 1 LASTPIN (-3100 4250) BN 5
J 0
(-3150 4260);
DISPLAY 0.617021 (-3150 4260);
PAINT PINK (-3150 4260);
FORCEPROP 2 LAST CDS_LIB mstr_standard
J 2
(-3150 4250);
DISPLAY 0.787234 (-3150 4250);
PAINT MONO (-3150 4250);
DISPLAY INVISIBLE (-3150 4250);
FORCEPROP 1 LAST BODY_TYPE PLUMBING
J 0
(-3150 4200);
DISPLAY 1.234043 (-3150 4200);
PAINT GREEN (-3150 4200);
DISPLAY INVISIBLE (-3150 4200);
FORCEPROP 1 LAST HDL_TAP TRUE
J 0
(-2825 4125);
DISPLAY 1.234043 (-2825 4125);
PAINT GREEN (-2825 4125);
DISPLAY INVISIBLE (-2825 4125);
FORCEPROP 1 LAST PATH I124
J 0
(-3150 4250);
DISPLAY 0.936170 (-3150 4250);
PAINT GREEN (-3150 4250);
DISPLAY INVISIBLE (-3150 4250);
FORCEADD TAP..6
(-3150 4200);
FORCEPROP 3 LASTPIN (-3100 4200) SIG_NAME M_C_MA<4>
J 0
(-3090 4210);
DISPLAY 0.659574 (-3090 4210);
PAINT MONO (-3090 4210);
DISPLAY INVISIBLE (-3090 4210);
FORCEPROP 1 LASTPIN (-3100 4200) BN 4
J 0
(-3150 4210);
DISPLAY 0.617021 (-3150 4210);
PAINT PINK (-3150 4210);
FORCEPROP 2 LAST CDS_LIB mstr_standard
J 2
(-3150 4200);
DISPLAY 0.787234 (-3150 4200);
PAINT MONO (-3150 4200);
DISPLAY INVISIBLE (-3150 4200);
FORCEPROP 1 LAST BODY_TYPE PLUMBING
J 0
(-3150 4150);
DISPLAY 1.234043 (-3150 4150);
PAINT GREEN (-3150 4150);
DISPLAY INVISIBLE (-3150 4150);
FORCEPROP 1 LAST HDL_TAP TRUE
J 0
(-2825 4075);
DISPLAY 1.234043 (-2825 4075);
PAINT GREEN (-2825 4075);
DISPLAY INVISIBLE (-2825 4075);
FORCEPROP 1 LAST PATH I125
J 0
(-3150 4200);
DISPLAY 0.936170 (-3150 4200);
PAINT GREEN (-3150 4200);
DISPLAY INVISIBLE (-3150 4200);
FORCEADD TAP..6
(-3150 4150);
FORCEPROP 3 LASTPIN (-3100 4150) SIG_NAME M_C_MA<3>
J 0
(-3090 4160);
DISPLAY 0.659574 (-3090 4160);
PAINT MONO (-3090 4160);
DISPLAY INVISIBLE (-3090 4160);
FORCEPROP 1 LASTPIN (-3100 4150) BN 3
J 0
(-3150 4160);
DISPLAY 0.617021 (-3150 4160);
PAINT PINK (-3150 4160);
FORCEPROP 2 LAST CDS_LIB mstr_standard
J 2
(-3150 4150);
DISPLAY 0.787234 (-3150 4150);
PAINT MONO (-3150 4150);
DISPLAY INVISIBLE (-3150 4150);
FORCEPROP 1 LAST BODY_TYPE PLUMBING
J 0
(-3150 4100);
DISPLAY 1.234043 (-3150 4100);
PAINT GREEN (-3150 4100);
DISPLAY INVISIBLE (-3150 4100);
FORCEPROP 1 LAST HDL_TAP TRUE
J 0
(-2825 4025);
DISPLAY 1.234043 (-2825 4025);
PAINT GREEN (-2825 4025);
DISPLAY INVISIBLE (-2825 4025);
FORCEPROP 1 LAST PATH I126
J 0
(-3150 4150);
DISPLAY 0.936170 (-3150 4150);
PAINT GREEN (-3150 4150);
DISPLAY INVISIBLE (-3150 4150);
FORCEADD OFFPAGE..1
(-3750 4900);
FORCEPROP 2 LAST $XR0 25 
J 0
(-3971 4900);
DISPLAY 0.638298 (-3971 4900);
PAINT MONO (-3971 4900);
FORCEPROP 2 LAST $XR1 47 
J 0
(-4061 4900);
DISPLAY 0.638298 (-4061 4900);
PAINT MONO (-4061 4900);
FORCEPROP 2 LAST CDS_LIB mstr_standard
J 0
(-3750 4900);
DISPLAY 0.787234 (-3750 4900);
PAINT MONO (-3750 4900);
DISPLAY INVISIBLE (-3750 4900);
FORCEPROP 1 LAST OFFPAGE TRUE
J 0
(-3425 4775);
DISPLAY 0.936170 (-3425 4775);
PAINT GREEN (-3425 4775);
DISPLAY INVISIBLE (-3425 4775);
FORCEPROP 1 LAST COMMENT_BODY TRUE
J 0
(-3625 4800);
DISPLAY 0.936170 (-3625 4800);
PAINT GREEN (-3625 4800);
DISPLAY INVISIBLE (-3625 4800);
FORCEPROP 2 LAST PATH I127
J 0
(-3700 4975);
DISPLAY 0.787234 (-3700 4975);
PAINT MONO (-3700 4975);
DISPLAY INVISIBLE (-3700 4975);
FORCEADD TAP..6
(-3150 4100);
FORCEPROP 3 LASTPIN (-3100 4100) SIG_NAME M_C_MA<2>
J 0
(-3090 4110);
DISPLAY 0.659574 (-3090 4110);
PAINT MONO (-3090 4110);
DISPLAY INVISIBLE (-3090 4110);
FORCEPROP 1 LASTPIN (-3100 4100) BN 2
J 0
(-3150 4110);
DISPLAY 0.617021 (-3150 4110);
PAINT PINK (-3150 4110);
FORCEPROP 2 LAST CDS_LIB mstr_standard
J 2
(-3150 4100);
DISPLAY 0.787234 (-3150 4100);
PAINT MONO (-3150 4100);
DISPLAY INVISIBLE (-3150 4100);
FORCEPROP 1 LAST BODY_TYPE PLUMBING
J 0
(-3150 4050);
DISPLAY 1.234043 (-3150 4050);
PAINT GREEN (-3150 4050);
DISPLAY INVISIBLE (-3150 4050);
FORCEPROP 1 LAST HDL_TAP TRUE
J 0
(-2825 3975);
DISPLAY 1.234043 (-2825 3975);
PAINT GREEN (-2825 3975);
DISPLAY INVISIBLE (-2825 3975);
FORCEPROP 1 LAST PATH I128
J 0
(-3150 4100);
DISPLAY 0.936170 (-3150 4100);
PAINT GREEN (-3150 4100);
DISPLAY INVISIBLE (-3150 4100);
FORCEADD TAP..6
(-3150 4050);
FORCEPROP 3 LASTPIN (-3100 4050) SIG_NAME M_C_MA<1>
J 0
(-3090 4060);
DISPLAY 0.659574 (-3090 4060);
PAINT MONO (-3090 4060);
DISPLAY INVISIBLE (-3090 4060);
FORCEPROP 1 LASTPIN (-3100 4050) BN 1
J 0
(-3150 4060);
DISPLAY 0.617021 (-3150 4060);
PAINT PINK (-3150 4060);
FORCEPROP 2 LAST CDS_LIB mstr_standard
J 2
(-3150 4050);
DISPLAY 0.787234 (-3150 4050);
PAINT MONO (-3150 4050);
DISPLAY INVISIBLE (-3150 4050);
FORCEPROP 1 LAST BODY_TYPE PLUMBING
J 0
(-3150 4000);
DISPLAY 1.234043 (-3150 4000);
PAINT GREEN (-3150 4000);
DISPLAY INVISIBLE (-3150 4000);
FORCEPROP 1 LAST HDL_TAP TRUE
J 0
(-2825 3925);
DISPLAY 1.234043 (-2825 3925);
PAINT GREEN (-2825 3925);
DISPLAY INVISIBLE (-2825 3925);
FORCEPROP 1 LAST PATH I129
J 0
(-3150 4050);
DISPLAY 0.936170 (-3150 4050);
PAINT GREEN (-3150 4050);
DISPLAY INVISIBLE (-3150 4050);
FORCEADD PVDDQ_ABC..1
(-1150 2550);
FORCEPROP 3 LASTPIN (-1150 2500) SIG_NAME PVDDQ_ABC\g
J 0
(-1140 2510);
DISPLAY 0.659574 (-1140 2510);
PAINT MONO (-1140 2510);
DISPLAY INVISIBLE (-1140 2510);
FORCEPROP 1 LAST VOLTAGE 1.2V
J 0
(-1195 2507);
DISPLAY 0.340426 (-1195 2507);
PAINT SKYBLUE (-1195 2507);
DISPLAY INVISIBLE (-1195 2507);
FORCEPROP 2 LAST BOM_COST MEM
J 0
(-1150 2555);
PAINT ORANGE (-1150 2555);
DISPLAY INVISIBLE (-1150 2555);
FORCEPROP 2 LAST CDS_LIB mstr_symbols
J 0
(-1150 2550);
PAINT ORANGE (-1150 2550);
DISPLAY INVISIBLE (-1150 2550);
FORCEPROP 1 LAST BODY_TYPE PLUMBING
J 0
(-1195 2507);
DISPLAY 0.340426 (-1195 2507);
PAINT GREEN (-1195 2507);
DISPLAY INVISIBLE (-1195 2507);
FORCEPROP 1 LAST PATH I13
J 0
(-1100 2575);
DISPLAY 0.872340 (-1100 2575);
PAINT AQUA (-1100 2575);
DISPLAY INVISIBLE (-1100 2575);
FORCEPROP 2 LAST ROOM DDR4_CH_B
J 0
(-1150 2555);
PAINT ORANGE (-1150 2555);
DISPLAY INVISIBLE (-1150 2555);
FORCEPROP 1 LAST HDL_POWER PVDDQ_ABC
J 1
(-1150 2600);
DISPLAY 0.872340 (-1150 2600);
PAINT GREEN (-1150 2600);
DISPLAY INVISIBLE (-1150 2600);
FORCEADD TAP..6
(-3150 4000);
FORCEPROP 3 LASTPIN (-3100 4000) SIG_NAME M_C_MA<0>
J 0
(-3090 4010);
DISPLAY 0.659574 (-3090 4010);
PAINT MONO (-3090 4010);
DISPLAY INVISIBLE (-3090 4010);
FORCEPROP 1 LASTPIN (-3100 4000) BN 0
J 0
(-3150 4010);
DISPLAY 0.617021 (-3150 4010);
PAINT PINK (-3150 4010);
FORCEPROP 2 LAST CDS_LIB mstr_standard
J 2
(-3150 4000);
DISPLAY 0.787234 (-3150 4000);
PAINT MONO (-3150 4000);
DISPLAY INVISIBLE (-3150 4000);
FORCEPROP 1 LAST BODY_TYPE PLUMBING
J 0
(-3150 3950);
DISPLAY 1.234043 (-3150 3950);
PAINT GREEN (-3150 3950);
DISPLAY INVISIBLE (-3150 3950);
FORCEPROP 1 LAST HDL_TAP TRUE
J 0
(-2825 3875);
DISPLAY 1.234043 (-2825 3875);
PAINT GREEN (-2825 3875);
DISPLAY INVISIBLE (-2825 3875);
FORCEPROP 1 LAST PATH I130
J 0
(-3150 4000);
DISPLAY 0.936170 (-3150 4000);
PAINT GREEN (-3150 4000);
DISPLAY INVISIBLE (-3150 4000);
FORCEADD TAP..6
(-3150 3900);
FORCEPROP 3 LASTPIN (-3100 3900) SIG_NAME M_C_BA<1>
J 0
(-3090 3910);
DISPLAY 0.659574 (-3090 3910);
PAINT MONO (-3090 3910);
DISPLAY INVISIBLE (-3090 3910);
FORCEPROP 1 LASTPIN (-3100 3900) BN 1
J 0
(-3150 3910);
DISPLAY 0.617021 (-3150 3910);
PAINT PINK (-3150 3910);
FORCEPROP 2 LAST CDS_LIB mstr_standard
J 0
(-3150 3900);
DISPLAY 0.787234 (-3150 3900);
PAINT MONO (-3150 3900);
DISPLAY INVISIBLE (-3150 3900);
FORCEPROP 1 LAST BODY_TYPE PLUMBING
J 0
(-3150 3850);
DISPLAY 1.234043 (-3150 3850);
PAINT GREEN (-3150 3850);
DISPLAY INVISIBLE (-3150 3850);
FORCEPROP 1 LAST HDL_TAP TRUE
J 0
(-2825 3775);
DISPLAY 1.234043 (-2825 3775);
PAINT GREEN (-2825 3775);
DISPLAY INVISIBLE (-2825 3775);
FORCEPROP 1 LAST PATH I131
J 0
(-3150 3900);
DISPLAY 0.936170 (-3150 3900);
PAINT GREEN (-3150 3900);
DISPLAY INVISIBLE (-3150 3900);
FORCEADD TAP..6
(-3150 3850);
FORCEPROP 3 LASTPIN (-3100 3850) SIG_NAME M_C_BA<0>
J 0
(-3090 3860);
DISPLAY 0.659574 (-3090 3860);
PAINT MONO (-3090 3860);
DISPLAY INVISIBLE (-3090 3860);
FORCEPROP 1 LASTPIN (-3100 3850) BN 0
J 0
(-3150 3860);
DISPLAY 0.617021 (-3150 3860);
PAINT PINK (-3150 3860);
FORCEPROP 2 LAST CDS_LIB mstr_standard
J 0
(-3150 3850);
DISPLAY 0.787234 (-3150 3850);
PAINT MONO (-3150 3850);
DISPLAY INVISIBLE (-3150 3850);
FORCEPROP 1 LAST BODY_TYPE PLUMBING
J 0
(-3150 3800);
DISPLAY 1.234043 (-3150 3800);
PAINT GREEN (-3150 3800);
DISPLAY INVISIBLE (-3150 3800);
FORCEPROP 1 LAST HDL_TAP TRUE
J 0
(-2825 3725);
DISPLAY 1.234043 (-2825 3725);
PAINT GREEN (-2825 3725);
DISPLAY INVISIBLE (-2825 3725);
FORCEPROP 1 LAST PATH I132
J 0
(-3150 3850);
DISPLAY 0.936170 (-3150 3850);
PAINT GREEN (-3150 3850);
DISPLAY INVISIBLE (-3150 3850);
FORCEADD TAP..6
(-3150 3750);
FORCEPROP 3 LASTPIN (-3100 3750) SIG_NAME M_C_BG<0>
J 0
(-3090 3760);
DISPLAY 0.659574 (-3090 3760);
PAINT MONO (-3090 3760);
DISPLAY INVISIBLE (-3090 3760);
FORCEPROP 1 LASTPIN (-3100 3750) BN 0
J 0
(-3150 3760);
DISPLAY 0.617021 (-3150 3760);
PAINT PINK (-3150 3760);
FORCEPROP 2 LAST CDS_LIB mstr_standard
J 0
(-3150 3750);
DISPLAY 0.787234 (-3150 3750);
PAINT MONO (-3150 3750);
DISPLAY INVISIBLE (-3150 3750);
FORCEPROP 1 LAST BODY_TYPE PLUMBING
J 0
(-3150 3700);
DISPLAY 1.234043 (-3150 3700);
PAINT GREEN (-3150 3700);
DISPLAY INVISIBLE (-3150 3700);
FORCEPROP 1 LAST HDL_TAP TRUE
J 0
(-2825 3625);
DISPLAY 1.234043 (-2825 3625);
PAINT GREEN (-2825 3625);
DISPLAY INVISIBLE (-2825 3625);
FORCEPROP 1 LAST PATH I133
J 0
(-3150 3750);
DISPLAY 0.936170 (-3150 3750);
PAINT GREEN (-3150 3750);
DISPLAY INVISIBLE (-3150 3750);
FORCEADD TAP..6
(-3150 3800);
FORCEPROP 3 LASTPIN (-3100 3800) SIG_NAME M_C_BG<1>
J 0
(-3090 3810);
DISPLAY 0.659574 (-3090 3810);
PAINT MONO (-3090 3810);
DISPLAY INVISIBLE (-3090 3810);
FORCEPROP 1 LASTPIN (-3100 3800) BN 1
J 0
(-3150 3810);
DISPLAY 0.617021 (-3150 3810);
PAINT PINK (-3150 3810);
FORCEPROP 2 LAST CDS_LIB mstr_standard
J 0
(-3150 3800);
DISPLAY 0.787234 (-3150 3800);
PAINT MONO (-3150 3800);
DISPLAY INVISIBLE (-3150 3800);
FORCEPROP 1 LAST BODY_TYPE PLUMBING
J 0
(-3150 3750);
DISPLAY 1.234043 (-3150 3750);
PAINT GREEN (-3150 3750);
DISPLAY INVISIBLE (-3150 3750);
FORCEPROP 1 LAST HDL_TAP TRUE
J 0
(-2825 3675);
DISPLAY 1.234043 (-2825 3675);
PAINT GREEN (-2825 3675);
DISPLAY INVISIBLE (-2825 3675);
FORCEPROP 1 LAST PATH I134
J 0
(-3150 3800);
DISPLAY 0.936170 (-3150 3800);
PAINT GREEN (-3150 3800);
DISPLAY INVISIBLE (-3150 3800);
FORCEADD OFFPAGE..1
(-3750 3450);
FORCEPROP 2 LAST $XR0 25 
J 0
(-3971 3450);
DISPLAY 0.638298 (-3971 3450);
PAINT MONO (-3971 3450);
FORCEPROP 2 LAST $XR1 47 
J 0
(-4061 3450);
DISPLAY 0.638298 (-4061 3450);
PAINT MONO (-4061 3450);
FORCEPROP 2 LAST CDS_LIB mstr_standard
J 0
(-3750 3450);
DISPLAY 0.787234 (-3750 3450);
PAINT MONO (-3750 3450);
DISPLAY INVISIBLE (-3750 3450);
FORCEPROP 1 LAST OFFPAGE TRUE
J 0
(-3425 3325);
DISPLAY 0.936170 (-3425 3325);
PAINT GREEN (-3425 3325);
DISPLAY INVISIBLE (-3425 3325);
FORCEPROP 1 LAST COMMENT_BODY TRUE
J 0
(-3625 3350);
DISPLAY 0.936170 (-3625 3350);
PAINT GREEN (-3625 3350);
DISPLAY INVISIBLE (-3625 3350);
FORCEPROP 2 LAST PATH I135
J 0
(-3700 3525);
DISPLAY 0.787234 (-3700 3525);
PAINT MONO (-3700 3525);
DISPLAY INVISIBLE (-3700 3525);
FORCEADD OFFPAGE..1
(-3750 3950);
FORCEPROP 2 LAST $XR0 25 
J 0
(-3971 3950);
DISPLAY 0.638298 (-3971 3950);
PAINT MONO (-3971 3950);
FORCEPROP 2 LAST $XR1 47 
J 0
(-4061 3950);
DISPLAY 0.638298 (-4061 3950);
PAINT MONO (-4061 3950);
FORCEPROP 2 LAST CDS_LIB mstr_standard
J 0
(-3750 3950);
DISPLAY 0.787234 (-3750 3950);
PAINT MONO (-3750 3950);
DISPLAY INVISIBLE (-3750 3950);
FORCEPROP 1 LAST OFFPAGE TRUE
J 0
(-3425 3825);
DISPLAY 0.936170 (-3425 3825);
PAINT GREEN (-3425 3825);
DISPLAY INVISIBLE (-3425 3825);
FORCEPROP 1 LAST COMMENT_BODY TRUE
J 0
(-3625 3850);
DISPLAY 0.936170 (-3625 3850);
PAINT GREEN (-3625 3850);
DISPLAY INVISIBLE (-3625 3850);
FORCEPROP 2 LAST PATH I136
J 0
(-3700 4025);
DISPLAY 0.787234 (-3700 4025);
PAINT MONO (-3700 4025);
DISPLAY INVISIBLE (-3700 4025);
FORCEADD OFFPAGE..1
(-3750 3850);
FORCEPROP 2 LAST $XR0 25 
J 0
(-3971 3850);
DISPLAY 0.638298 (-3971 3850);
PAINT MONO (-3971 3850);
FORCEPROP 2 LAST $XR1 47 
J 0
(-4061 3850);
DISPLAY 0.638298 (-4061 3850);
PAINT MONO (-4061 3850);
FORCEPROP 2 LAST CDS_LIB mstr_standard
J 0
(-3750 3850);
DISPLAY 0.787234 (-3750 3850);
PAINT MONO (-3750 3850);
DISPLAY INVISIBLE (-3750 3850);
FORCEPROP 1 LAST OFFPAGE TRUE
J 0
(-3425 3725);
DISPLAY 0.936170 (-3425 3725);
PAINT GREEN (-3425 3725);
DISPLAY INVISIBLE (-3425 3725);
FORCEPROP 1 LAST COMMENT_BODY TRUE
J 0
(-3625 3750);
DISPLAY 0.936170 (-3625 3750);
PAINT GREEN (-3625 3750);
DISPLAY INVISIBLE (-3625 3750);
FORCEPROP 2 LAST PATH I137
J 0
(-3700 3925);
DISPLAY 0.787234 (-3700 3925);
PAINT MONO (-3700 3925);
DISPLAY INVISIBLE (-3700 3925);
FORCEADD TAP..6
(-3150 2800);
FORCEPROP 3 LASTPIN (-3100 2800) SIG_NAME M_C_ECC<7>
J 0
(-3090 2810);
DISPLAY 0.659574 (-3090 2810);
PAINT MONO (-3090 2810);
DISPLAY INVISIBLE (-3090 2810);
FORCEPROP 1 LASTPIN (-3100 2800) BN 7
J 0
(-3150 2810);
DISPLAY 0.617021 (-3150 2810);
PAINT PINK (-3150 2810);
FORCEPROP 2 LAST CDS_LIB mstr_standard
J 0
(-3150 2800);
DISPLAY 0.787234 (-3150 2800);
PAINT MONO (-3150 2800);
DISPLAY INVISIBLE (-3150 2800);
FORCEPROP 1 LAST BODY_TYPE PLUMBING
J 0
(-3150 2750);
DISPLAY 1.234043 (-3150 2750);
PAINT GREEN (-3150 2750);
DISPLAY INVISIBLE (-3150 2750);
FORCEPROP 1 LAST HDL_TAP TRUE
J 0
(-2825 2675);
DISPLAY 1.234043 (-2825 2675);
PAINT GREEN (-2825 2675);
DISPLAY INVISIBLE (-2825 2675);
FORCEPROP 1 LAST PATH I138
J 0
(-3150 2800);
DISPLAY 0.936170 (-3150 2800);
PAINT GREEN (-3150 2800);
DISPLAY INVISIBLE (-3150 2800);
FORCEADD TAP..6
(-3150 2750);
FORCEPROP 3 LASTPIN (-3100 2750) SIG_NAME M_C_ECC<6>
J 0
(-3090 2760);
DISPLAY 0.659574 (-3090 2760);
PAINT MONO (-3090 2760);
DISPLAY INVISIBLE (-3090 2760);
FORCEPROP 1 LASTPIN (-3100 2750) BN 6
J 0
(-3150 2760);
DISPLAY 0.617021 (-3150 2760);
PAINT PINK (-3150 2760);
FORCEPROP 2 LAST CDS_LIB mstr_standard
J 0
(-3150 2750);
DISPLAY 0.787234 (-3150 2750);
PAINT MONO (-3150 2750);
DISPLAY INVISIBLE (-3150 2750);
FORCEPROP 1 LAST BODY_TYPE PLUMBING
J 0
(-3150 2700);
DISPLAY 1.234043 (-3150 2700);
PAINT GREEN (-3150 2700);
DISPLAY INVISIBLE (-3150 2700);
FORCEPROP 1 LAST HDL_TAP TRUE
J 0
(-2825 2625);
DISPLAY 1.234043 (-2825 2625);
PAINT GREEN (-2825 2625);
DISPLAY INVISIBLE (-2825 2625);
FORCEPROP 1 LAST PATH I139
J 0
(-3150 2750);
DISPLAY 0.936170 (-3150 2750);
PAINT GREEN (-3150 2750);
DISPLAY INVISIBLE (-3150 2750);
FORCEADD TAP..6
R 2
(900 4600);
FORCEPROP 3 LASTPIN (850 4600) SIG_NAME M_C_DQS_DN<12>
J 0
(860 4610);
DISPLAY 0.659574 (860 4610);
PAINT MONO (860 4610);
DISPLAY INVISIBLE (860 4610);
FORCEPROP 1 LASTPIN (850 4600) BN 12
J 2
(900 4610);
DISPLAY 0.617021 (900 4610);
PAINT PINK (900 4610);
FORCEPROP 2 LAST CDS_LIB mstr_standard
J 0
(900 4600);
DISPLAY 0.787234 (900 4600);
PAINT MONO (900 4600);
DISPLAY INVISIBLE (900 4600);
FORCEPROP 1 LAST BODY_TYPE PLUMBING
J 2
(900 4550);
DISPLAY 1.234043 (900 4550);
PAINT GREEN (900 4550);
DISPLAY INVISIBLE (900 4550);
FORCEPROP 1 LAST HDL_TAP TRUE
J 2
(575 4475);
DISPLAY 1.234043 (575 4475);
PAINT GREEN (575 4475);
DISPLAY INVISIBLE (575 4475);
FORCEPROP 1 LAST PATH I14
J 2
(900 4600);
DISPLAY 0.936170 (900 4600);
PAINT GREEN (900 4600);
DISPLAY INVISIBLE (900 4600);
FORCEADD TAP..6
(-3150 2700);
FORCEPROP 3 LASTPIN (-3100 2700) SIG_NAME M_C_ECC<5>
J 0
(-3090 2710);
DISPLAY 0.659574 (-3090 2710);
PAINT MONO (-3090 2710);
DISPLAY INVISIBLE (-3090 2710);
FORCEPROP 1 LASTPIN (-3100 2700) BN 5
J 0
(-3150 2710);
DISPLAY 0.617021 (-3150 2710);
PAINT PINK (-3150 2710);
FORCEPROP 2 LAST CDS_LIB mstr_standard
J 0
(-3150 2700);
DISPLAY 0.787234 (-3150 2700);
PAINT MONO (-3150 2700);
DISPLAY INVISIBLE (-3150 2700);
FORCEPROP 1 LAST BODY_TYPE PLUMBING
J 0
(-3150 2650);
DISPLAY 1.234043 (-3150 2650);
PAINT GREEN (-3150 2650);
DISPLAY INVISIBLE (-3150 2650);
FORCEPROP 1 LAST HDL_TAP TRUE
J 0
(-2825 2575);
DISPLAY 1.234043 (-2825 2575);
PAINT GREEN (-2825 2575);
DISPLAY INVISIBLE (-2825 2575);
FORCEPROP 1 LAST PATH I140
J 0
(-3150 2700);
DISPLAY 0.936170 (-3150 2700);
PAINT GREEN (-3150 2700);
DISPLAY INVISIBLE (-3150 2700);
FORCEADD TAP..6
(-3150 2650);
FORCEPROP 3 LASTPIN (-3100 2650) SIG_NAME M_C_ECC<4>
J 0
(-3090 2660);
DISPLAY 0.659574 (-3090 2660);
PAINT MONO (-3090 2660);
DISPLAY INVISIBLE (-3090 2660);
FORCEPROP 1 LASTPIN (-3100 2650) BN 4
J 0
(-3150 2660);
DISPLAY 0.617021 (-3150 2660);
PAINT PINK (-3150 2660);
FORCEPROP 2 LAST CDS_LIB mstr_standard
J 0
(-3150 2650);
DISPLAY 0.787234 (-3150 2650);
PAINT MONO (-3150 2650);
DISPLAY INVISIBLE (-3150 2650);
FORCEPROP 1 LAST BODY_TYPE PLUMBING
J 0
(-3150 2600);
DISPLAY 1.234043 (-3150 2600);
PAINT GREEN (-3150 2600);
DISPLAY INVISIBLE (-3150 2600);
FORCEPROP 1 LAST HDL_TAP TRUE
J 0
(-2825 2525);
DISPLAY 1.234043 (-2825 2525);
PAINT GREEN (-2825 2525);
DISPLAY INVISIBLE (-2825 2525);
FORCEPROP 1 LAST PATH I141
J 0
(-3150 2650);
DISPLAY 0.936170 (-3150 2650);
PAINT GREEN (-3150 2650);
DISPLAY INVISIBLE (-3150 2650);
FORCEADD TAP..6
(-3150 2600);
FORCEPROP 3 LASTPIN (-3100 2600) SIG_NAME M_C_ECC<3>
J 0
(-3090 2610);
DISPLAY 0.659574 (-3090 2610);
PAINT MONO (-3090 2610);
DISPLAY INVISIBLE (-3090 2610);
FORCEPROP 1 LASTPIN (-3100 2600) BN 3
J 0
(-3150 2610);
DISPLAY 0.617021 (-3150 2610);
PAINT PINK (-3150 2610);
FORCEPROP 2 LAST CDS_LIB mstr_standard
J 0
(-3150 2600);
DISPLAY 0.787234 (-3150 2600);
PAINT MONO (-3150 2600);
DISPLAY INVISIBLE (-3150 2600);
FORCEPROP 1 LAST BODY_TYPE PLUMBING
J 0
(-3150 2550);
DISPLAY 1.234043 (-3150 2550);
PAINT GREEN (-3150 2550);
DISPLAY INVISIBLE (-3150 2550);
FORCEPROP 1 LAST HDL_TAP TRUE
J 0
(-2825 2475);
DISPLAY 1.234043 (-2825 2475);
PAINT GREEN (-2825 2475);
DISPLAY INVISIBLE (-2825 2475);
FORCEPROP 1 LAST PATH I142
J 0
(-3150 2600);
DISPLAY 0.936170 (-3150 2600);
PAINT GREEN (-3150 2600);
DISPLAY INVISIBLE (-3150 2600);
FORCEADD TAP..6
(-3150 2550);
FORCEPROP 3 LASTPIN (-3100 2550) SIG_NAME M_C_ECC<2>
J 0
(-3090 2560);
DISPLAY 0.659574 (-3090 2560);
PAINT MONO (-3090 2560);
DISPLAY INVISIBLE (-3090 2560);
FORCEPROP 1 LASTPIN (-3100 2550) BN 2
J 0
(-3150 2560);
DISPLAY 0.617021 (-3150 2560);
PAINT PINK (-3150 2560);
FORCEPROP 2 LAST CDS_LIB mstr_standard
J 0
(-3150 2550);
DISPLAY 0.787234 (-3150 2550);
PAINT MONO (-3150 2550);
DISPLAY INVISIBLE (-3150 2550);
FORCEPROP 1 LAST BODY_TYPE PLUMBING
J 0
(-3150 2500);
DISPLAY 1.234043 (-3150 2500);
PAINT GREEN (-3150 2500);
DISPLAY INVISIBLE (-3150 2500);
FORCEPROP 1 LAST HDL_TAP TRUE
J 0
(-2825 2425);
DISPLAY 1.234043 (-2825 2425);
PAINT GREEN (-2825 2425);
DISPLAY INVISIBLE (-2825 2425);
FORCEPROP 1 LAST PATH I143
J 0
(-3150 2550);
DISPLAY 0.936170 (-3150 2550);
PAINT GREEN (-3150 2550);
DISPLAY INVISIBLE (-3150 2550);
FORCEADD TAP..6
(-3150 2500);
FORCEPROP 3 LASTPIN (-3100 2500) SIG_NAME M_C_ECC<1>
J 0
(-3090 2510);
DISPLAY 0.659574 (-3090 2510);
PAINT MONO (-3090 2510);
DISPLAY INVISIBLE (-3090 2510);
FORCEPROP 1 LASTPIN (-3100 2500) BN 1
J 0
(-3150 2510);
DISPLAY 0.617021 (-3150 2510);
PAINT PINK (-3150 2510);
FORCEPROP 2 LAST CDS_LIB mstr_standard
J 0
(-3150 2500);
DISPLAY 0.787234 (-3150 2500);
PAINT MONO (-3150 2500);
DISPLAY INVISIBLE (-3150 2500);
FORCEPROP 1 LAST BODY_TYPE PLUMBING
J 0
(-3150 2450);
DISPLAY 1.234043 (-3150 2450);
PAINT GREEN (-3150 2450);
DISPLAY INVISIBLE (-3150 2450);
FORCEPROP 1 LAST HDL_TAP TRUE
J 0
(-2825 2375);
DISPLAY 1.234043 (-2825 2375);
PAINT GREEN (-2825 2375);
DISPLAY INVISIBLE (-2825 2375);
FORCEPROP 1 LAST PATH I144
J 0
(-3150 2500);
DISPLAY 0.936170 (-3150 2500);
PAINT GREEN (-3150 2500);
DISPLAY INVISIBLE (-3150 2500);
FORCEADD TAP..6
(-3150 2450);
FORCEPROP 3 LASTPIN (-3100 2450) SIG_NAME M_C_ECC<0>
J 0
(-3090 2460);
DISPLAY 0.659574 (-3090 2460);
PAINT MONO (-3090 2460);
DISPLAY INVISIBLE (-3090 2460);
FORCEPROP 1 LASTPIN (-3100 2450) BN 0
J 0
(-3150 2460);
DISPLAY 0.617021 (-3150 2460);
PAINT PINK (-3150 2460);
FORCEPROP 2 LAST CDS_LIB mstr_standard
J 0
(-3150 2450);
DISPLAY 0.787234 (-3150 2450);
PAINT MONO (-3150 2450);
DISPLAY INVISIBLE (-3150 2450);
FORCEPROP 1 LAST BODY_TYPE PLUMBING
J 0
(-3150 2400);
DISPLAY 1.234043 (-3150 2400);
PAINT GREEN (-3150 2400);
DISPLAY INVISIBLE (-3150 2400);
FORCEPROP 1 LAST HDL_TAP TRUE
J 0
(-2825 2325);
DISPLAY 1.234043 (-2825 2325);
PAINT GREEN (-2825 2325);
DISPLAY INVISIBLE (-2825 2325);
FORCEPROP 1 LAST PATH I145
J 0
(-3150 2450);
DISPLAY 0.936170 (-3150 2450);
PAINT GREEN (-3150 2450);
DISPLAY INVISIBLE (-3150 2450);
FORCEADD OFFPAGE..1
(-3750 2800);
FORCEPROP 2 LAST $XR0 25 
J 0
(-4001 2800);
DISPLAY 0.638298 (-4001 2800);
PAINT MONO (-4001 2800);
FORCEPROP 2 LAST $XR1 47 
J 0
(-4091 2800);
DISPLAY 0.638298 (-4091 2800);
PAINT MONO (-4091 2800);
FORCEPROP 2 LAST CDS_LIB mstr_standard
J 0
(-3750 2800);
DISPLAY 0.787234 (-3750 2800);
PAINT MONO (-3750 2800);
DISPLAY INVISIBLE (-3750 2800);
FORCEPROP 1 LAST OFFPAGE TRUE
J 0
(-3425 2675);
DISPLAY 0.936170 (-3425 2675);
PAINT GREEN (-3425 2675);
DISPLAY INVISIBLE (-3425 2675);
FORCEPROP 1 LAST COMMENT_BODY TRUE
J 0
(-3625 2700);
DISPLAY 0.936170 (-3625 2700);
PAINT GREEN (-3625 2700);
DISPLAY INVISIBLE (-3625 2700);
FORCEPROP 2 LAST PATH I146
J 0
(-3700 2875);
DISPLAY 0.787234 (-3700 2875);
PAINT MONO (-3700 2875);
DISPLAY INVISIBLE (-3700 2875);
FORCEADD OFFPAGE..1
(-3750 2750);
FORCEPROP 2 LAST $XR0 21 
J 0
(-3971 2750);
DISPLAY 0.638298 (-3971 2750);
PAINT MONO (-3971 2750);
FORCEPROP 2 LAST $XR1 43 
J 0
(-4061 2750);
DISPLAY 0.638298 (-4061 2750);
PAINT MONO (-4061 2750);
FORCEPROP 2 LAST $XR2 44 
J 0
(-4151 2750);
DISPLAY 0.638298 (-4151 2750);
PAINT MONO (-4151 2750);
FORCEPROP 2 LAST $XR3 45 
J 0
(-4241 2750);
DISPLAY 0.638298 (-4241 2750);
PAINT MONO (-4241 2750);
FORCEPROP 2 LAST $XR4 46 
J 0
(-4331 2750);
DISPLAY 0.638298 (-4331 2750);
PAINT MONO (-4331 2750);
FORCEPROP 2 LAST $XR5 47 
J 0
(-4421 2750);
DISPLAY 0.638298 (-4421 2750);
PAINT MONO (-4421 2750);
FORCEPROP 2 LAST CDS_LIB mstr_standard
J 0
(-3750 2750);
DISPLAY 0.787234 (-3750 2750);
PAINT MONO (-3750 2750);
DISPLAY INVISIBLE (-3750 2750);
FORCEPROP 1 LAST OFFPAGE TRUE
J 0
(-3425 2625);
DISPLAY 0.936170 (-3425 2625);
PAINT GREEN (-3425 2625);
DISPLAY INVISIBLE (-3425 2625);
FORCEPROP 1 LAST COMMENT_BODY TRUE
J 0
(-3625 2650);
DISPLAY 0.936170 (-3625 2650);
PAINT GREEN (-3625 2650);
DISPLAY INVISIBLE (-3625 2650);
FORCEPROP 2 LAST PATH I147
J 0
(-3700 2825);
DISPLAY 0.787234 (-3700 2825);
PAINT MONO (-3700 2825);
DISPLAY INVISIBLE (-3700 2825);
FORCEADD OFFPAGE..5
(-3975 2200);
FORCEPROP 2 LAST $XR0 47 
J 0
(-4229 2200);
DISPLAY 0.638298 (-4229 2200);
PAINT MONO (-4229 2200);
FORCEPROP 2 LAST $XR1 25 
J 0
(-4319 2200);
DISPLAY 0.638298 (-4319 2200);
PAINT MONO (-4319 2200);
FORCEPROP 2 LAST CDS_LIB mstr_standard
J 0
(-3975 2200);
DISPLAY 0.787234 (-3975 2200);
PAINT MONO (-3975 2200);
DISPLAY INVISIBLE (-3975 2200);
FORCEPROP 1 LAST OFFPAGE TRUE
J 0
(-3650 2075);
DISPLAY 1.404255 (-3650 2075);
PAINT GREEN (-3650 2075);
DISPLAY INVISIBLE (-3650 2075);
FORCEPROP 1 LAST COMMENT_BODY TRUE
J 0
(-3875 2125);
DISPLAY 1.404255 (-3875 2125);
PAINT GREEN (-3875 2125);
DISPLAY INVISIBLE (-3875 2125);
FORCEPROP 2 LAST PATH I148
J 0
(-3925 2275);
DISPLAY 0.787234 (-3925 2275);
PAINT MONO (-3925 2275);
DISPLAY INVISIBLE (-3925 2275);
FORCEADD OFFPAGE..1
(-3950 2150);
FORCEPROP 2 LAST $XR0 25 
J 0
(-4201 2150);
DISPLAY 0.638298 (-4201 2150);
PAINT MONO (-4201 2150);
FORCEPROP 2 LAST $XR1 47 
J 0
(-4291 2150);
DISPLAY 0.638298 (-4291 2150);
PAINT MONO (-4291 2150);
FORCEPROP 2 LAST CDS_LIB mstr_standard
J 0
(-3950 2150);
DISPLAY 0.787234 (-3950 2150);
PAINT MONO (-3950 2150);
DISPLAY INVISIBLE (-3950 2150);
FORCEPROP 1 LAST OFFPAGE TRUE
J 0
(-3625 2025);
DISPLAY 0.936170 (-3625 2025);
PAINT GREEN (-3625 2025);
DISPLAY INVISIBLE (-3625 2025);
FORCEPROP 1 LAST COMMENT_BODY TRUE
J 0
(-3825 2050);
DISPLAY 0.936170 (-3825 2050);
PAINT GREEN (-3825 2050);
DISPLAY INVISIBLE (-3825 2050);
FORCEPROP 2 LAST PATH I149
J 0
(-3900 2225);
DISPLAY 0.787234 (-3900 2225);
PAINT MONO (-3900 2225);
DISPLAY INVISIBLE (-3900 2225);
FORCEADD TAP..6
R 2
(900 4700);
FORCEPROP 3 LASTPIN (850 4700) SIG_NAME M_C_DQS_DN<13>
J 0
(860 4710);
DISPLAY 0.659574 (860 4710);
PAINT MONO (860 4710);
DISPLAY INVISIBLE (860 4710);
FORCEPROP 1 LASTPIN (850 4700) BN 13
J 2
(900 4710);
DISPLAY 0.617021 (900 4710);
PAINT PINK (900 4710);
FORCEPROP 2 LAST CDS_LIB mstr_standard
J 0
(900 4700);
DISPLAY 0.787234 (900 4700);
PAINT MONO (900 4700);
DISPLAY INVISIBLE (900 4700);
FORCEPROP 1 LAST BODY_TYPE PLUMBING
J 2
(900 4650);
DISPLAY 1.234043 (900 4650);
PAINT GREEN (900 4650);
DISPLAY INVISIBLE (900 4650);
FORCEPROP 1 LAST HDL_TAP TRUE
J 2
(575 4575);
DISPLAY 1.234043 (575 4575);
PAINT GREEN (575 4575);
DISPLAY INVISIBLE (575 4575);
FORCEPROP 1 LAST PATH I15
J 2
(900 4700);
DISPLAY 0.936170 (900 4700);
PAINT GREEN (900 4700);
DISPLAY INVISIBLE (900 4700);
FORCEADD OFFPAGE..6
(-3750 2850);
FORCEPROP 2 LAST $XR0 25 
J 0
(-4029 2850);
DISPLAY 0.638298 (-4029 2850);
PAINT MONO (-4029 2850);
FORCEPROP 2 LAST $XR1 47 
J 0
(-4119 2850);
DISPLAY 0.638298 (-4119 2850);
PAINT MONO (-4119 2850);
FORCEPROP 2 LAST CDS_LIB mstr_standard
J 0
(-3750 2850);
DISPLAY 0.787234 (-3750 2850);
PAINT MONO (-3750 2850);
DISPLAY INVISIBLE (-3750 2850);
FORCEPROP 1 LAST OFFPAGE TRUE
J 0
(-3425 2725);
DISPLAY 0.936170 (-3425 2725);
PAINT GREEN (-3425 2725);
DISPLAY INVISIBLE (-3425 2725);
FORCEPROP 1 LAST COMMENT_BODY TRUE
J 0
(-3650 2775);
DISPLAY 0.936170 (-3650 2775);
PAINT GREEN (-3650 2775);
DISPLAY INVISIBLE (-3650 2775);
FORCEPROP 2 LAST PATH I150
J 0
(-3700 2925);
DISPLAY 0.787234 (-3700 2925);
PAINT MONO (-3700 2925);
DISPLAY INVISIBLE (-3700 2925);
FORCEADD OFFPAGE..1
(-4800 1700);
FORCEPROP 2 LAST $XR0 98 
J 0
(-5051 1700);
DISPLAY 0.638298 (-5051 1700);
PAINT MONO (-5051 1700);
FORCEPROP 2 LAST $XR1 47 
J 0
(-5141 1700);
DISPLAY 0.638298 (-5141 1700);
PAINT MONO (-5141 1700);
FORCEPROP 2 LAST CDS_LIB mstr_standard
J 0
(-4800 1700);
DISPLAY 0.787234 (-4800 1700);
PAINT MONO (-4800 1700);
DISPLAY INVISIBLE (-4800 1700);
FORCEPROP 1 LAST OFFPAGE TRUE
J 0
(-4475 1575);
DISPLAY 0.936170 (-4475 1575);
PAINT GREEN (-4475 1575);
DISPLAY INVISIBLE (-4475 1575);
FORCEPROP 1 LAST COMMENT_BODY TRUE
J 0
(-4675 1600);
DISPLAY 0.936170 (-4675 1600);
PAINT GREEN (-4675 1600);
DISPLAY INVISIBLE (-4675 1600);
FORCEPROP 2 LAST PATH I151
J 0
(-4750 1775);
DISPLAY 0.787234 (-4750 1775);
PAINT MONO (-4750 1775);
DISPLAY INVISIBLE (-4750 1775);
FORCEADD TAP..6
(-3150 3100);
FORCEPROP 3 LASTPIN (-3100 3100) SIG_NAME M_C_CKE<3>
J 0
(-3090 3110);
DISPLAY 0.659574 (-3090 3110);
PAINT MONO (-3090 3110);
DISPLAY INVISIBLE (-3090 3110);
FORCEPROP 1 LASTPIN (-3100 3100) BN 3
J 0
(-3150 3110);
DISPLAY 0.617021 (-3150 3110);
PAINT PINK (-3150 3110);
FORCEPROP 2 LAST CDS_LIB mstr_standard
J 0
(-3150 3100);
DISPLAY 0.787234 (-3150 3100);
PAINT MONO (-3150 3100);
DISPLAY INVISIBLE (-3150 3100);
FORCEPROP 1 LAST BODY_TYPE PLUMBING
J 0
(-3150 3050);
DISPLAY 1.234043 (-3150 3050);
PAINT GREEN (-3150 3050);
DISPLAY INVISIBLE (-3150 3050);
FORCEPROP 1 LAST HDL_TAP TRUE
J 0
(-2825 2975);
DISPLAY 1.234043 (-2825 2975);
PAINT GREEN (-2825 2975);
DISPLAY INVISIBLE (-2825 2975);
FORCEPROP 1 LAST PATH I152
J 0
(-3150 3100);
DISPLAY 0.936170 (-3150 3100);
PAINT GREEN (-3150 3100);
DISPLAY INVISIBLE (-3150 3100);
FORCEADD OFFPAGE..1
(-3750 3150);
FORCEPROP 2 LAST $XR0 25 
J 0
(-3971 3150);
DISPLAY 0.638298 (-3971 3150);
PAINT MONO (-3971 3150);
FORCEPROP 2 LAST $XR1 47 
J 0
(-4061 3150);
DISPLAY 0.638298 (-4061 3150);
PAINT MONO (-4061 3150);
FORCEPROP 2 LAST CDS_LIB mstr_standard
J 0
(-3750 3150);
DISPLAY 0.787234 (-3750 3150);
PAINT MONO (-3750 3150);
DISPLAY INVISIBLE (-3750 3150);
FORCEPROP 1 LAST OFFPAGE TRUE
J 0
(-3425 3025);
DISPLAY 0.936170 (-3425 3025);
PAINT GREEN (-3425 3025);
DISPLAY INVISIBLE (-3425 3025);
FORCEPROP 1 LAST COMMENT_BODY TRUE
J 0
(-3625 3050);
DISPLAY 0.936170 (-3625 3050);
PAINT GREEN (-3625 3050);
DISPLAY INVISIBLE (-3625 3050);
FORCEPROP 2 LAST PATH I153
J 0
(-3700 3225);
DISPLAY 0.787234 (-3700 3225);
PAINT MONO (-3700 3225);
DISPLAY INVISIBLE (-3700 3225);
FORCEADD TAP..6
(-3150 3050);
FORCEPROP 3 LASTPIN (-3100 3050) SIG_NAME M_C_CKE<2>
J 0
(-3090 3060);
DISPLAY 0.659574 (-3090 3060);
PAINT MONO (-3090 3060);
DISPLAY INVISIBLE (-3090 3060);
FORCEPROP 1 LASTPIN (-3100 3050) BN 2
J 0
(-3150 3060);
DISPLAY 0.617021 (-3150 3060);
PAINT PINK (-3150 3060);
FORCEPROP 2 LAST CDS_LIB mstr_standard
J 0
(-3150 3050);
DISPLAY 0.787234 (-3150 3050);
PAINT MONO (-3150 3050);
DISPLAY INVISIBLE (-3150 3050);
FORCEPROP 1 LAST BODY_TYPE PLUMBING
J 0
(-3150 3000);
DISPLAY 1.234043 (-3150 3000);
PAINT GREEN (-3150 3000);
DISPLAY INVISIBLE (-3150 3000);
FORCEPROP 1 LAST HDL_TAP TRUE
J 0
(-2825 2925);
DISPLAY 1.234043 (-2825 2925);
PAINT GREEN (-2825 2925);
DISPLAY INVISIBLE (-2825 2925);
FORCEPROP 1 LAST PATH I154
J 0
(-3150 3050);
DISPLAY 0.936170 (-3150 3050);
PAINT GREEN (-3150 3050);
DISPLAY INVISIBLE (-3150 3050);
FORCEADD TAP..6
(-3150 2950);
FORCEPROP 3 LASTPIN (-3100 2950) SIG_NAME M_C_ODT<3>
J 0
(-3090 2960);
DISPLAY 0.659574 (-3090 2960);
PAINT MONO (-3090 2960);
DISPLAY INVISIBLE (-3090 2960);
FORCEPROP 1 LASTPIN (-3100 2950) BN 3
J 0
(-3150 2960);
DISPLAY 0.617021 (-3150 2960);
PAINT PINK (-3150 2960);
FORCEPROP 2 LAST CDS_LIB mstr_standard
J 0
(-3150 2950);
DISPLAY 0.787234 (-3150 2950);
PAINT MONO (-3150 2950);
DISPLAY INVISIBLE (-3150 2950);
FORCEPROP 1 LAST BODY_TYPE PLUMBING
J 0
(-3150 2900);
DISPLAY 1.234043 (-3150 2900);
PAINT GREEN (-3150 2900);
DISPLAY INVISIBLE (-3150 2900);
FORCEPROP 1 LAST HDL_TAP TRUE
J 0
(-2825 2825);
DISPLAY 1.234043 (-2825 2825);
PAINT GREEN (-2825 2825);
DISPLAY INVISIBLE (-2825 2825);
FORCEPROP 1 LAST PATH I155
J 0
(-3150 2950);
DISPLAY 0.936170 (-3150 2950);
PAINT GREEN (-3150 2950);
DISPLAY INVISIBLE (-3150 2950);
FORCEADD OFFPAGE..1
(-3750 3000);
FORCEPROP 2 LAST $XR0 25 
J 0
(-3971 3000);
DISPLAY 0.638298 (-3971 3000);
PAINT MONO (-3971 3000);
FORCEPROP 2 LAST $XR1 47 
J 0
(-4061 3000);
DISPLAY 0.638298 (-4061 3000);
PAINT MONO (-4061 3000);
FORCEPROP 2 LAST CDS_LIB mstr_standard
J 0
(-3750 3000);
DISPLAY 0.787234 (-3750 3000);
PAINT MONO (-3750 3000);
DISPLAY INVISIBLE (-3750 3000);
FORCEPROP 1 LAST OFFPAGE TRUE
J 0
(-3425 2875);
DISPLAY 0.936170 (-3425 2875);
PAINT GREEN (-3425 2875);
DISPLAY INVISIBLE (-3425 2875);
FORCEPROP 1 LAST COMMENT_BODY TRUE
J 0
(-3625 2900);
DISPLAY 0.936170 (-3625 2900);
PAINT GREEN (-3625 2900);
DISPLAY INVISIBLE (-3625 2900);
FORCEPROP 2 LAST PATH I156
J 0
(-3700 3075);
DISPLAY 0.787234 (-3700 3075);
PAINT MONO (-3700 3075);
DISPLAY INVISIBLE (-3700 3075);
FORCEADD TAP..6
(-3150 2900);
FORCEPROP 3 LASTPIN (-3100 2900) SIG_NAME M_C_ODT<2>
J 0
(-3090 2910);
DISPLAY 0.659574 (-3090 2910);
PAINT MONO (-3090 2910);
DISPLAY INVISIBLE (-3090 2910);
FORCEPROP 1 LASTPIN (-3100 2900) BN 2
J 0
(-3150 2910);
DISPLAY 0.617021 (-3150 2910);
PAINT PINK (-3150 2910);
FORCEPROP 2 LAST CDS_LIB mstr_standard
J 0
(-3150 2900);
DISPLAY 0.787234 (-3150 2900);
PAINT MONO (-3150 2900);
DISPLAY INVISIBLE (-3150 2900);
FORCEPROP 1 LAST BODY_TYPE PLUMBING
J 0
(-3150 2850);
DISPLAY 1.234043 (-3150 2850);
PAINT GREEN (-3150 2850);
DISPLAY INVISIBLE (-3150 2850);
FORCEPROP 1 LAST HDL_TAP TRUE
J 0
(-2825 2775);
DISPLAY 1.234043 (-2825 2775);
PAINT GREEN (-2825 2775);
DISPLAY INVISIBLE (-2825 2775);
FORCEPROP 1 LAST PATH I157
J 0
(-3150 2900);
DISPLAY 0.936170 (-3150 2900);
PAINT GREEN (-3150 2900);
DISPLAY INVISIBLE (-3150 2900);
FORCEADD TAP..6
(-3150 3350);
FORCEPROP 3 LASTPIN (-3100 3350) SIG_NAME M_C_CS_N<7>
J 0
(-3090 3360);
DISPLAY 0.659574 (-3090 3360);
PAINT MONO (-3090 3360);
DISPLAY INVISIBLE (-3090 3360);
FORCEPROP 1 LASTPIN (-3100 3350) BN 7
J 0
(-3150 3360);
DISPLAY 0.617021 (-3150 3360);
PAINT PINK (-3150 3360);
FORCEPROP 2 LAST CDS_LIB mstr_standard
J 0
(-3150 3350);
DISPLAY 0.787234 (-3150 3350);
PAINT MONO (-3150 3350);
DISPLAY INVISIBLE (-3150 3350);
FORCEPROP 1 LAST BODY_TYPE PLUMBING
J 0
(-3150 3300);
DISPLAY 1.234043 (-3150 3300);
PAINT GREEN (-3150 3300);
DISPLAY INVISIBLE (-3150 3300);
FORCEPROP 1 LAST HDL_TAP TRUE
J 0
(-2825 3225);
DISPLAY 1.234043 (-2825 3225);
PAINT GREEN (-2825 3225);
DISPLAY INVISIBLE (-2825 3225);
FORCEPROP 1 LAST PATH I158
J 0
(-3150 3350);
DISPLAY 0.936170 (-3150 3350);
PAINT GREEN (-3150 3350);
DISPLAY INVISIBLE (-3150 3350);
FORCEADD TAP..6
(-3150 3300);
FORCEPROP 3 LASTPIN (-3100 3300) SIG_NAME M_C_CS_N<6>
J 0
(-3090 3310);
DISPLAY 0.659574 (-3090 3310);
PAINT MONO (-3090 3310);
DISPLAY INVISIBLE (-3090 3310);
FORCEPROP 1 LASTPIN (-3100 3300) BN 6
J 0
(-3150 3310);
DISPLAY 0.617021 (-3150 3310);
PAINT PINK (-3150 3310);
FORCEPROP 2 LAST CDS_LIB mstr_standard
J 0
(-3150 3300);
DISPLAY 0.787234 (-3150 3300);
PAINT MONO (-3150 3300);
DISPLAY INVISIBLE (-3150 3300);
FORCEPROP 1 LAST BODY_TYPE PLUMBING
J 0
(-3150 3250);
DISPLAY 1.234043 (-3150 3250);
PAINT GREEN (-3150 3250);
DISPLAY INVISIBLE (-3150 3250);
FORCEPROP 1 LAST HDL_TAP TRUE
J 0
(-2825 3175);
DISPLAY 1.234043 (-2825 3175);
PAINT GREEN (-2825 3175);
DISPLAY INVISIBLE (-2825 3175);
FORCEPROP 1 LAST PATH I159
J 0
(-3150 3300);
DISPLAY 0.936170 (-3150 3300);
PAINT GREEN (-3150 3300);
DISPLAY INVISIBLE (-3150 3300);
FORCEADD TAP..6
R 2
(700 4750);
FORCEPROP 3 LASTPIN (650 4750) SIG_NAME M_C_DQS_DP<13>
J 0
(660 4760);
DISPLAY 0.659574 (660 4760);
PAINT MONO (660 4760);
DISPLAY INVISIBLE (660 4760);
FORCEPROP 1 LASTPIN (650 4750) BN 13
J 2
(700 4760);
DISPLAY 0.617021 (700 4760);
PAINT PINK (700 4760);
FORCEPROP 2 LAST CDS_LIB mstr_standard
J 0
(700 4750);
DISPLAY 0.787234 (700 4750);
PAINT MONO (700 4750);
DISPLAY INVISIBLE (700 4750);
FORCEPROP 1 LAST BODY_TYPE PLUMBING
J 2
(700 4700);
DISPLAY 1.234043 (700 4700);
PAINT GREEN (700 4700);
DISPLAY INVISIBLE (700 4700);
FORCEPROP 1 LAST HDL_TAP TRUE
J 2
(375 4625);
DISPLAY 1.234043 (375 4625);
PAINT WHITE (375 4625);
DISPLAY INVISIBLE (375 4625);
FORCEPROP 1 LAST PATH I16
J 2
(700 4750);
DISPLAY 0.936170 (700 4750);
PAINT GREEN (700 4750);
DISPLAY INVISIBLE (700 4750);
FORCEADD TAP..6
(-3150 3250);
FORCEPROP 3 LASTPIN (-3100 3250) SIG_NAME M_C_CS_N<5>
J 0
(-3090 3260);
DISPLAY 0.659574 (-3090 3260);
PAINT MONO (-3090 3260);
DISPLAY INVISIBLE (-3090 3260);
FORCEPROP 1 LASTPIN (-3100 3250) BN 5
J 0
(-3150 3260);
DISPLAY 0.617021 (-3150 3260);
PAINT PINK (-3150 3260);
FORCEPROP 2 LAST CDS_LIB mstr_standard
J 0
(-3150 3250);
DISPLAY 0.787234 (-3150 3250);
PAINT MONO (-3150 3250);
DISPLAY INVISIBLE (-3150 3250);
FORCEPROP 1 LAST BODY_TYPE PLUMBING
J 0
(-3150 3200);
DISPLAY 1.234043 (-3150 3200);
PAINT GREEN (-3150 3200);
DISPLAY INVISIBLE (-3150 3200);
FORCEPROP 1 LAST HDL_TAP TRUE
J 0
(-2825 3125);
DISPLAY 1.234043 (-2825 3125);
PAINT GREEN (-2825 3125);
DISPLAY INVISIBLE (-2825 3125);
FORCEPROP 1 LAST PATH I160
J 0
(-3150 3250);
DISPLAY 0.936170 (-3150 3250);
PAINT GREEN (-3150 3250);
DISPLAY INVISIBLE (-3150 3250);
FORCEADD TAP..6
(-3150 3200);
FORCEPROP 3 LASTPIN (-3100 3200) SIG_NAME M_C_CS_N<4>
J 0
(-3090 3210);
DISPLAY 0.659574 (-3090 3210);
PAINT MONO (-3090 3210);
DISPLAY INVISIBLE (-3090 3210);
FORCEPROP 1 LASTPIN (-3100 3200) BN 4
J 0
(-3150 3210);
DISPLAY 0.617021 (-3150 3210);
PAINT PINK (-3150 3210);
FORCEPROP 2 LAST CDS_LIB mstr_standard
J 0
(-3150 3200);
DISPLAY 0.787234 (-3150 3200);
PAINT MONO (-3150 3200);
DISPLAY INVISIBLE (-3150 3200);
FORCEPROP 1 LAST BODY_TYPE PLUMBING
J 0
(-3150 3150);
DISPLAY 1.234043 (-3150 3150);
PAINT GREEN (-3150 3150);
DISPLAY INVISIBLE (-3150 3150);
FORCEPROP 1 LAST HDL_TAP TRUE
J 0
(-2825 3075);
DISPLAY 1.234043 (-2825 3075);
PAINT GREEN (-2825 3075);
DISPLAY INVISIBLE (-2825 3075);
FORCEPROP 1 LAST PATH I161
J 0
(-3150 3200);
DISPLAY 0.936170 (-3150 3200);
PAINT GREEN (-3150 3200);
DISPLAY INVISIBLE (-3150 3200);
FORCEADD OFFPAGE..1
(-3750 3400);
FORCEPROP 2 LAST $XR0 25 
J 0
(-3971 3400);
DISPLAY 0.638298 (-3971 3400);
PAINT MONO (-3971 3400);
FORCEPROP 2 LAST $XR1 47 
J 0
(-4061 3400);
DISPLAY 0.638298 (-4061 3400);
PAINT MONO (-4061 3400);
FORCEPROP 2 LAST CDS_LIB mstr_standard
J 0
(-3750 3400);
DISPLAY 0.787234 (-3750 3400);
PAINT MONO (-3750 3400);
DISPLAY INVISIBLE (-3750 3400);
FORCEPROP 1 LAST OFFPAGE TRUE
J 0
(-3425 3275);
DISPLAY 0.936170 (-3425 3275);
PAINT GREEN (-3425 3275);
DISPLAY INVISIBLE (-3425 3275);
FORCEPROP 1 LAST COMMENT_BODY TRUE
J 0
(-3625 3300);
DISPLAY 0.936170 (-3625 3300);
PAINT GREEN (-3625 3300);
DISPLAY INVISIBLE (-3625 3300);
FORCEPROP 2 LAST PATH I162
J 0
(-3700 3475);
DISPLAY 0.787234 (-3700 3475);
PAINT MONO (-3700 3475);
DISPLAY INVISIBLE (-3700 3475);
FORCEADD TAP..6
(-3150 3650);
FORCEPROP 3 LASTPIN (-3100 3650) SIG_NAME M_C_CLK_DP<3>
J 0
(-3090 3660);
DISPLAY 0.659574 (-3090 3660);
PAINT MONO (-3090 3660);
DISPLAY INVISIBLE (-3090 3660);
FORCEPROP 1 LASTPIN (-3100 3650) BN 3
J 0
(-3150 3660);
DISPLAY 0.617021 (-3150 3660);
PAINT PINK (-3150 3660);
FORCEPROP 2 LAST CDS_LIB mstr_standard
J 0
(-3150 3650);
DISPLAY 0.787234 (-3150 3650);
PAINT MONO (-3150 3650);
DISPLAY INVISIBLE (-3150 3650);
FORCEPROP 1 LAST BODY_TYPE PLUMBING
J 0
(-3150 3600);
DISPLAY 1.234043 (-3150 3600);
PAINT GREEN (-3150 3600);
DISPLAY INVISIBLE (-3150 3600);
FORCEPROP 1 LAST HDL_TAP TRUE
J 0
(-2825 3525);
DISPLAY 1.234043 (-2825 3525);
PAINT GREEN (-2825 3525);
DISPLAY INVISIBLE (-2825 3525);
FORCEPROP 1 LAST PATH I163
J 0
(-3150 3650);
DISPLAY 0.936170 (-3150 3650);
PAINT GREEN (-3150 3650);
DISPLAY INVISIBLE (-3150 3650);
FORCEADD TAP..6
(-3150 3550);
FORCEPROP 3 LASTPIN (-3100 3550) SIG_NAME M_C_CLK_DP<2>
J 0
(-3090 3560);
DISPLAY 0.659574 (-3090 3560);
PAINT MONO (-3090 3560);
DISPLAY INVISIBLE (-3090 3560);
FORCEPROP 1 LASTPIN (-3100 3550) BN 2
J 0
(-3150 3560);
DISPLAY 0.617021 (-3150 3560);
PAINT PINK (-3150 3560);
FORCEPROP 2 LAST CDS_LIB mstr_standard
J 0
(-3150 3550);
DISPLAY 0.787234 (-3150 3550);
PAINT MONO (-3150 3550);
DISPLAY INVISIBLE (-3150 3550);
FORCEPROP 1 LAST BODY_TYPE PLUMBING
J 0
(-3150 3500);
DISPLAY 1.234043 (-3150 3500);
PAINT GREEN (-3150 3500);
DISPLAY INVISIBLE (-3150 3500);
FORCEPROP 1 LAST HDL_TAP TRUE
J 0
(-2825 3425);
DISPLAY 1.234043 (-2825 3425);
PAINT GREEN (-2825 3425);
DISPLAY INVISIBLE (-2825 3425);
FORCEPROP 1 LAST PATH I164
J 0
(-3150 3550);
DISPLAY 0.936170 (-3150 3550);
PAINT GREEN (-3150 3550);
DISPLAY INVISIBLE (-3150 3550);
FORCEADD TAP..6
(-3350 3600);
FORCEPROP 3 LASTPIN (-3300 3600) SIG_NAME M_C_CLK_DN<3>
J 0
(-3290 3610);
DISPLAY 0.659574 (-3290 3610);
PAINT MONO (-3290 3610);
DISPLAY INVISIBLE (-3290 3610);
FORCEPROP 1 LASTPIN (-3300 3600) BN 3
J 0
(-3350 3610);
DISPLAY 0.617021 (-3350 3610);
PAINT PINK (-3350 3610);
FORCEPROP 2 LAST CDS_LIB mstr_standard
J 0
(-3350 3600);
DISPLAY 0.787234 (-3350 3600);
PAINT MONO (-3350 3600);
DISPLAY INVISIBLE (-3350 3600);
FORCEPROP 1 LAST BODY_TYPE PLUMBING
J 0
(-3350 3550);
DISPLAY 1.234043 (-3350 3550);
PAINT GREEN (-3350 3550);
DISPLAY INVISIBLE (-3350 3550);
FORCEPROP 1 LAST HDL_TAP TRUE
J 0
(-3025 3475);
DISPLAY 1.234043 (-3025 3475);
PAINT GREEN (-3025 3475);
DISPLAY INVISIBLE (-3025 3475);
FORCEPROP 1 LAST PATH I165
J 0
(-3350 3600);
DISPLAY 0.936170 (-3350 3600);
PAINT GREEN (-3350 3600);
DISPLAY INVISIBLE (-3350 3600);
FORCEADD TAP..6
(-3350 3500);
FORCEPROP 3 LASTPIN (-3300 3500) SIG_NAME M_C_CLK_DN<2>
J 0
(-3290 3510);
DISPLAY 0.659574 (-3290 3510);
PAINT MONO (-3290 3510);
DISPLAY INVISIBLE (-3290 3510);
FORCEPROP 1 LASTPIN (-3300 3500) BN 2
J 0
(-3350 3510);
DISPLAY 0.617021 (-3350 3510);
PAINT PINK (-3350 3510);
FORCEPROP 2 LAST CDS_LIB mstr_standard
J 0
(-3350 3500);
DISPLAY 0.787234 (-3350 3500);
PAINT MONO (-3350 3500);
DISPLAY INVISIBLE (-3350 3500);
FORCEPROP 1 LAST BODY_TYPE PLUMBING
J 0
(-3350 3450);
DISPLAY 1.234043 (-3350 3450);
PAINT GREEN (-3350 3450);
DISPLAY INVISIBLE (-3350 3450);
FORCEPROP 1 LAST HDL_TAP TRUE
J 0
(-3025 3375);
DISPLAY 1.234043 (-3025 3375);
PAINT GREEN (-3025 3375);
DISPLAY INVISIBLE (-3025 3375);
FORCEPROP 1 LAST PATH I166
J 0
(-3350 3500);
DISPLAY 0.936170 (-3350 3500);
PAINT GREEN (-3350 3500);
DISPLAY INVISIBLE (-3350 3500);
FORCEADD OFFPAGE..1
(-3950 3700);
FORCEPROP 2 LAST $XR0 25 
J 0
(-4171 3700);
DISPLAY 0.638298 (-4171 3700);
PAINT MONO (-4171 3700);
FORCEPROP 2 LAST $XR1 47 
J 0
(-4261 3700);
DISPLAY 0.638298 (-4261 3700);
PAINT MONO (-4261 3700);
FORCEPROP 2 LAST CDS_LIB mstr_standard
J 0
(-3950 3700);
DISPLAY 0.787234 (-3950 3700);
PAINT MONO (-3950 3700);
DISPLAY INVISIBLE (-3950 3700);
FORCEPROP 1 LAST OFFPAGE TRUE
J 0
(-3625 3575);
DISPLAY 0.936170 (-3625 3575);
PAINT GREEN (-3625 3575);
DISPLAY INVISIBLE (-3625 3575);
FORCEPROP 1 LAST COMMENT_BODY TRUE
J 0
(-3825 3600);
DISPLAY 0.936170 (-3825 3600);
PAINT GREEN (-3825 3600);
DISPLAY INVISIBLE (-3825 3600);
FORCEPROP 2 LAST PATH I167
J 0
(-3900 3775);
DISPLAY 0.787234 (-3900 3775);
PAINT MONO (-3900 3775);
DISPLAY INVISIBLE (-3900 3775);
FORCEADD OFFPAGE..1
(-3950 3650);
FORCEPROP 2 LAST $XR0 25 
J 0
(-4171 3650);
DISPLAY 0.638298 (-4171 3650);
PAINT MONO (-4171 3650);
FORCEPROP 2 LAST $XR1 47 
J 0
(-4261 3650);
DISPLAY 0.638298 (-4261 3650);
PAINT MONO (-4261 3650);
FORCEPROP 2 LAST CDS_LIB mstr_standard
J 0
(-3950 3650);
DISPLAY 0.787234 (-3950 3650);
PAINT MONO (-3950 3650);
DISPLAY INVISIBLE (-3950 3650);
FORCEPROP 1 LAST OFFPAGE TRUE
J 0
(-3625 3525);
DISPLAY 0.936170 (-3625 3525);
PAINT GREEN (-3625 3525);
DISPLAY INVISIBLE (-3625 3525);
FORCEPROP 1 LAST COMMENT_BODY TRUE
J 0
(-3825 3550);
DISPLAY 0.936170 (-3825 3550);
PAINT GREEN (-3825 3550);
DISPLAY INVISIBLE (-3825 3550);
FORCEPROP 2 LAST PATH I168
J 0
(-3900 3725);
DISPLAY 0.787234 (-3900 3725);
PAINT MONO (-3900 3725);
DISPLAY INVISIBLE (-3900 3725);
FORCEADD OFFPAGE..1
(-3750 1800);
FORCEPROP 2 LAST $XR0 99 
J 0
(-4001 1800);
DISPLAY 0.638298 (-4001 1800);
PAINT MONO (-4001 1800);
FORCEPROP 2 LAST $XR1 43 
J 0
(-4091 1800);
DISPLAY 0.638298 (-4091 1800);
PAINT MONO (-4091 1800);
FORCEPROP 2 LAST $XR2 44 
J 0
(-4181 1800);
DISPLAY 0.638298 (-4181 1800);
PAINT MONO (-4181 1800);
FORCEPROP 2 LAST $XR3 45 
J 0
(-4271 1800);
DISPLAY 0.638298 (-4271 1800);
PAINT MONO (-4271 1800);
FORCEPROP 2 LAST $XR4 46 
J 0
(-4361 1800);
DISPLAY 0.638298 (-4361 1800);
PAINT MONO (-4361 1800);
FORCEPROP 2 LAST $XR5 47 
J 0
(-4451 1800);
DISPLAY 0.638298 (-4451 1800);
PAINT MONO (-4451 1800);
FORCEPROP 2 LAST CDS_LIB mstr_standard
J 0
(-3750 1800);
DISPLAY 0.787234 (-3750 1800);
PAINT MONO (-3750 1800);
DISPLAY INVISIBLE (-3750 1800);
FORCEPROP 1 LAST OFFPAGE TRUE
J 0
(-3425 1675);
DISPLAY 0.936170 (-3425 1675);
PAINT GREEN (-3425 1675);
DISPLAY INVISIBLE (-3425 1675);
FORCEPROP 1 LAST COMMENT_BODY TRUE
J 0
(-3625 1700);
DISPLAY 0.936170 (-3625 1700);
PAINT GREEN (-3625 1700);
DISPLAY INVISIBLE (-3625 1700);
FORCEPROP 2 LAST PATH I169
J 0
(-3700 1875);
DISPLAY 0.787234 (-3700 1875);
PAINT MONO (-3700 1875);
DISPLAY INVISIBLE (-3700 1875);
FORCEADD TAP..6
R 2
(700 4650);
FORCEPROP 3 LASTPIN (650 4650) SIG_NAME M_C_DQS_DP<12>
J 0
(660 4660);
DISPLAY 0.659574 (660 4660);
PAINT MONO (660 4660);
DISPLAY INVISIBLE (660 4660);
FORCEPROP 1 LASTPIN (650 4650) BN 12
J 2
(700 4660);
DISPLAY 0.617021 (700 4660);
PAINT PINK (700 4660);
FORCEPROP 2 LAST CDS_LIB mstr_standard
J 0
(700 4650);
DISPLAY 0.787234 (700 4650);
PAINT MONO (700 4650);
DISPLAY INVISIBLE (700 4650);
FORCEPROP 1 LAST BODY_TYPE PLUMBING
J 2
(700 4600);
DISPLAY 1.234043 (700 4600);
PAINT GREEN (700 4600);
DISPLAY INVISIBLE (700 4600);
FORCEPROP 1 LAST HDL_TAP TRUE
J 2
(375 4525);
DISPLAY 1.234043 (375 4525);
PAINT WHITE (375 4525);
DISPLAY INVISIBLE (375 4525);
FORCEPROP 1 LAST PATH I17
J 2
(700 4650);
DISPLAY 0.936170 (700 4650);
PAINT GREEN (700 4650);
DISPLAY INVISIBLE (700 4650);
FORCEADD OFFPAGE..6
(-3750 1850);
FORCEPROP 2 LAST $XR0 43 
J 0
(-4029 1850);
DISPLAY 0.638298 (-4029 1850);
PAINT MONO (-4029 1850);
FORCEPROP 2 LAST $XR1 44 
J 0
(-4119 1850);
DISPLAY 0.638298 (-4119 1850);
PAINT MONO (-4119 1850);
FORCEPROP 2 LAST $XR2 45 
J 0
(-4209 1850);
DISPLAY 0.638298 (-4209 1850);
PAINT MONO (-4209 1850);
FORCEPROP 2 LAST $XR3 46 
J 0
(-4299 1850);
DISPLAY 0.638298 (-4299 1850);
PAINT MONO (-4299 1850);
FORCEPROP 2 LAST $XR4 47 
J 0
(-4389 1850);
DISPLAY 0.638298 (-4389 1850);
PAINT MONO (-4389 1850);
FORCEPROP 2 LAST $XR5 99 
J 0
(-4479 1850);
DISPLAY 0.638298 (-4479 1850);
PAINT MONO (-4479 1850);
FORCEPROP 2 LAST CDS_LIB mstr_standard
J 0
(-3750 1850);
DISPLAY 0.787234 (-3750 1850);
PAINT MONO (-3750 1850);
DISPLAY INVISIBLE (-3750 1850);
FORCEPROP 1 LAST OFFPAGE TRUE
J 0
(-3425 1725);
DISPLAY 0.936170 (-3425 1725);
PAINT GREEN (-3425 1725);
DISPLAY INVISIBLE (-3425 1725);
FORCEPROP 1 LAST COMMENT_BODY TRUE
J 0
(-3650 1775);
DISPLAY 0.936170 (-3650 1775);
PAINT GREEN (-3650 1775);
DISPLAY INVISIBLE (-3650 1775);
FORCEPROP 2 LAST PATH I170
J 0
(-3700 1925);
DISPLAY 0.787234 (-3700 1925);
PAINT MONO (-3700 1925);
DISPLAY INVISIBLE (-3700 1925);
FORCEADD SCONN288_H44441003..4
(-100 2000);
FORCEPROP 1 LAST LOCATION J6U2
J 0
(-550 3100);
DISPLAY 0.617021 (-550 3100);
PAINT AQUA (-550 3100);
FORCEPROP 1 LAST PART_NUMBER H44441-003
J 0
(-550 950);
DISPLAY 0.617021 (-550 950);
PAINT BLUE (-550 950);
FORCEPROP 1 LAST MATERIAL SCONN
J 0
(-550 3050);
DISPLAY 0.617021 (-550 3050);
PAINT SKYBLUE (-550 3050);
FORCEPROP 2 LASTPIN (-600 2550) $PN 77
J 2
(-610 2560);
DISPLAY 0.617021 (-610 2560);
PAINT ORANGE (-610 2560);
FORCEPROP 2 LASTPIN (-600 2500) $PN 221
J 2
(-610 2510);
DISPLAY 0.617021 (-610 2510);
PAINT ORANGE (-610 2510);
FORCEPROP 2 LASTPIN (-600 2850) $PN 142
J 2
(-610 2860);
DISPLAY 0.617021 (-610 2860);
PAINT ORANGE (-610 2860);
FORCEPROP 2 LASTPIN (-600 2800) $PN 143
J 2
(-610 2810);
DISPLAY 0.617021 (-610 2810);
PAINT ORANGE (-610 2810);
FORCEPROP 2 LASTPIN (-600 2750) $PN 288
J 2
(-610 2760);
DISPLAY 0.617021 (-610 2760);
PAINT ORANGE (-610 2760);
FORCEPROP 2 LASTPIN (-600 2700) $PN 286
J 2
(-610 2710);
DISPLAY 0.617021 (-610 2710);
PAINT ORANGE (-610 2710);
FORCEPROP 2 LASTPIN (-600 2650) $PN 287
J 2
(-610 2660);
DISPLAY 0.617021 (-610 2660);
PAINT ORANGE (-610 2660);
FORCEPROP 2 LASTPIN (-600 2400) $PN 59
J 2
(-610 2410);
DISPLAY 0.617021 (-610 2410);
PAINT ORANGE (-610 2410);
FORCEPROP 2 LASTPIN (-600 2350) $PN 61
J 2
(-610 2360);
DISPLAY 0.617021 (-610 2360);
PAINT ORANGE (-610 2360);
FORCEPROP 2 LASTPIN (-600 2300) $PN 64
J 2
(-610 2310);
DISPLAY 0.617021 (-610 2310);
PAINT ORANGE (-610 2310);
FORCEPROP 2 LASTPIN (-600 2250) $PN 67
J 2
(-610 2260);
DISPLAY 0.617021 (-610 2260);
PAINT ORANGE (-610 2260);
FORCEPROP 2 LASTPIN (-600 2200) $PN 70
J 2
(-610 2210);
DISPLAY 0.617021 (-610 2210);
PAINT ORANGE (-610 2210);
FORCEPROP 2 LASTPIN (-600 2150) $PN 73
J 2
(-610 2160);
DISPLAY 0.617021 (-610 2160);
PAINT ORANGE (-610 2160);
FORCEPROP 2 LASTPIN (-600 2100) $PN 76
J 2
(-610 2110);
DISPLAY 0.617021 (-610 2110);
PAINT ORANGE (-610 2110);
FORCEPROP 2 LASTPIN (-600 2050) $PN 80
J 2
(-610 2060);
DISPLAY 0.617021 (-610 2060);
PAINT ORANGE (-610 2060);
FORCEPROP 2 LASTPIN (-600 2000) $PN 83
J 2
(-610 2010);
DISPLAY 0.617021 (-610 2010);
PAINT ORANGE (-610 2010);
FORCEPROP 2 LASTPIN (-600 1950) $PN 85
J 2
(-610 1960);
DISPLAY 0.617021 (-610 1960);
PAINT ORANGE (-610 1960);
FORCEPROP 2 LASTPIN (-600 1900) $PN 88
J 2
(-610 1910);
DISPLAY 0.617021 (-610 1910);
PAINT ORANGE (-610 1910);
FORCEPROP 2 LASTPIN (-600 1850) $PN 90
J 2
(-610 1860);
DISPLAY 0.617021 (-610 1860);
PAINT ORANGE (-610 1860);
FORCEPROP 2 LASTPIN (-600 1800) $PN 92
J 2
(-610 1810);
DISPLAY 0.617021 (-610 1810);
PAINT ORANGE (-610 1810);
FORCEPROP 2 LASTPIN (-600 1750) $PN 204
J 2
(-610 1760);
DISPLAY 0.617021 (-610 1760);
PAINT ORANGE (-610 1760);
FORCEPROP 2 LASTPIN (-600 1700) $PN 206
J 2
(-610 1710);
DISPLAY 0.617021 (-610 1710);
PAINT ORANGE (-610 1710);
FORCEPROP 2 LASTPIN (-600 1650) $PN 209
J 2
(-610 1660);
DISPLAY 0.617021 (-610 1660);
PAINT ORANGE (-610 1660);
FORCEPROP 2 LASTPIN (-600 1600) $PN 212
J 2
(-610 1610);
DISPLAY 0.617021 (-610 1610);
PAINT ORANGE (-610 1610);
FORCEPROP 2 LASTPIN (-600 1550) $PN 215
J 2
(-610 1560);
DISPLAY 0.617021 (-610 1560);
PAINT ORANGE (-610 1560);
FORCEPROP 2 LASTPIN (-600 1500) $PN 217
J 2
(-610 1510);
DISPLAY 0.617021 (-610 1510);
PAINT ORANGE (-610 1510);
FORCEPROP 2 LASTPIN (-600 1450) $PN 220
J 2
(-610 1460);
DISPLAY 0.617021 (-610 1460);
PAINT ORANGE (-610 1460);
FORCEPROP 2 LASTPIN (-600 1400) $PN 223
J 2
(-610 1410);
DISPLAY 0.617021 (-610 1410);
PAINT ORANGE (-610 1410);
FORCEPROP 2 LASTPIN (-600 1350) $PN 226
J 2
(-610 1360);
DISPLAY 0.617021 (-610 1360);
PAINT ORANGE (-610 1360);
FORCEPROP 2 LASTPIN (-600 1300) $PN 229
J 2
(-610 1310);
DISPLAY 0.617021 (-610 1310);
PAINT ORANGE (-610 1310);
FORCEPROP 2 LASTPIN (-600 1250) $PN 231
J 2
(-610 1260);
DISPLAY 0.617021 (-610 1260);
PAINT ORANGE (-610 1260);
FORCEPROP 2 LASTPIN (-600 1200) $PN 233
J 2
(-610 1210);
DISPLAY 0.617021 (-610 1210);
PAINT ORANGE (-610 1210);
FORCEPROP 2 LASTPIN (-600 1150) $PN 236
J 2
(-610 1160);
DISPLAY 0.617021 (-610 1160);
PAINT ORANGE (-610 1160);
FORCEPROP 2 LASTPIN (400 2850) $PN 1
J 0
(410 2860);
DISPLAY 0.617021 (410 2860);
PAINT ORANGE (410 2860);
FORCEPROP 2 LASTPIN (400 2800) $PN 145
J 0
(410 2810);
DISPLAY 0.617021 (410 2810);
PAINT ORANGE (410 2810);
FORCEPROP 1 LAST PACK_TYPE PIP
J 0
(-550 3150);
PAINT SKYBLUE (-550 3150);
DISPLAY INVISIBLE (-550 3150);
FORCEPROP 2 LAST BOM_COST MEM
J 0
(-100 2000);
PAINT ORANGE (-100 2000);
DISPLAY INVISIBLE (-100 2000);
FORCEPROP 2 LAST CDS_LIB mstr_sconn
J 0
(-100 2000);
PAINT ORANGE (-100 2000);
DISPLAY INVISIBLE (-100 2000);
FORCEPROP 2 LAST SEC_TYPE PIP
J 0
(-550 3150);
DISPLAY 1.021277 (-550 3150);
PAINT ORANGE (-550 3150);
DISPLAY INVISIBLE (-550 3150);
FORCEPROP 2 LAST SEC 4
J 0
(-550 3150);
DISPLAY 0.680851 (-550 3150);
PAINT MONO (-550 3150);
DISPLAY INVISIBLE (-550 3150);
FORCEPROP 2 LAST CDS_LOCATION J6U2
J 0
(-550 3100);
DISPLAY 0.617021 (-550 3100);
PAINT AQUA (-550 3100);
DISPLAY INVISIBLE (-550 3100);
FORCEPROP 1 LAST PATH I171
J 0
(-100 3050);
PAINT GREEN (-100 3050);
DISPLAY INVISIBLE (-100 3050);
FORCEPROP 2 LAST ROOM DDR4_CH_C1
J 0
(-100 2000);
PAINT ORANGE (-100 2000);
DISPLAY INVISIBLE (-100 2000);
FORCEADD GND..1
R 2
(2500 1300);
FORCEPROP 3 LASTPIN (2500 1350) SIG_NAME GND\g
J 0
(2510 1360);
DISPLAY 0.659574 (2510 1360);
PAINT MONO (2510 1360);
DISPLAY INVISIBLE (2510 1360);
FORCEPROP 1 LAST VOLTAGE 0
J 0
(2500 1300);
PAINT SKYBLUE (2500 1300);
DISPLAY INVISIBLE (2500 1300);
FORCEPROP 2 LAST CDS_LIB mstr_symbols
J 0
(2500 1300);
DISPLAY 0.787234 (2500 1300);
PAINT MONO (2500 1300);
DISPLAY INVISIBLE (2500 1300);
FORCEPROP 1 LAST SIZE 1B
J 2
(2425 1250);
DISPLAY 1.170213 (2425 1250);
PAINT GREEN (2425 1250);
DISPLAY INVISIBLE (2425 1250);
FORCEPROP 2 LAST BOM_COST MEM
J 0
(2500 1305);
PAINT ORANGE (2500 1305);
DISPLAY INVISIBLE (2500 1305);
FORCEPROP 1 LAST BODY_TYPE PLUMBING
J 2
(2545 1257);
DISPLAY 0.340426 (2545 1257);
PAINT GREEN (2545 1257);
DISPLAY INVISIBLE (2545 1257);
FORCEPROP 1 LAST PATH I172
J 2
(2425 1300);
DISPLAY 1.404255 (2425 1300);
PAINT GREEN (2425 1300);
DISPLAY INVISIBLE (2425 1300);
FORCEPROP 2 LAST ROOM DDR4_CH_B
J 0
(2500 1305);
PAINT ORANGE (2500 1305);
DISPLAY INVISIBLE (2500 1305);
FORCEPROP 1 LAST HDL_POWER GND
J 2
(2500 1450);
DISPLAY 0.553191 (2500 1450);
PAINT GREEN (2500 1450);
DISPLAY INVISIBLE (2500 1450);
FORCEADD OFFPAGE..5
(-4125 2500);
FORCEPROP 2 LAST $XR0 43 
J 0
(-4379 2500);
DISPLAY 0.638298 (-4379 2500);
PAINT MONO (-4379 2500);
FORCEPROP 2 LAST $XR1 44 
J 0
(-4469 2500);
DISPLAY 0.638298 (-4469 2500);
PAINT MONO (-4469 2500);
FORCEPROP 2 LAST $XR2 45 
J 0
(-4559 2500);
DISPLAY 0.638298 (-4559 2500);
PAINT MONO (-4559 2500);
FORCEPROP 2 LAST $XR3 46 
J 0
(-4649 2500);
DISPLAY 0.638298 (-4649 2500);
PAINT MONO (-4649 2500);
FORCEPROP 2 LAST $XR4 47 
J 0
(-4739 2500);
DISPLAY 0.638298 (-4739 2500);
PAINT MONO (-4739 2500);
FORCEPROP 2 LAST $XR5 49 
J 0
(-4829 2500);
DISPLAY 0.638298 (-4829 2500);
PAINT MONO (-4829 2500);
FORCEPROP 2 LAST $XR6 50 
J 0
(-4919 2500);
DISPLAY 0.638298 (-4919 2500);
PAINT MONO (-4919 2500);
FORCEPROP 2 LAST $XR7 51 
J 0
(-5009 2500);
DISPLAY 0.638298 (-5009 2500);
PAINT MONO (-5009 2500);
FORCEPROP 2 LAST $XR8 52 
J 0
(-5099 2500);
DISPLAY 0.638298 (-5099 2500);
PAINT MONO (-5099 2500);
FORCEPROP 2 LAST $XR9 53 
J 0
(-5189 2500);
DISPLAY 0.638298 (-5189 2500);
PAINT MONO (-5189 2500);
FORCEPROP 2 LAST $XR10 54 
J 0
(-4379 2464);
DISPLAY 0.638298 (-4379 2464);
PAINT MONO (-4379 2464);
FORCEPROP 2 LAST $XR11 77 
J 0
(-4469 2464);
DISPLAY 0.638298 (-4469 2464);
PAINT MONO (-4469 2464);
FORCEPROP 2 LAST $XR12 78 
J 0
(-4559 2464);
DISPLAY 0.638298 (-4559 2464);
PAINT MONO (-4559 2464);
FORCEPROP 2 LAST $XR13 79 
J 0
(-4649 2464);
DISPLAY 0.638298 (-4649 2464);
PAINT MONO (-4649 2464);
FORCEPROP 2 LAST $XR14 80 
J 0
(-4739 2464);
DISPLAY 0.638298 (-4739 2464);
PAINT MONO (-4739 2464);
FORCEPROP 2 LAST $XR15 81 
J 0
(-4829 2464);
DISPLAY 0.638298 (-4829 2464);
PAINT MONO (-4829 2464);
FORCEPROP 2 LAST $XR16 82 
J 0
(-4919 2464);
DISPLAY 0.638298 (-4919 2464);
PAINT MONO (-4919 2464);
FORCEPROP 2 LAST $XR17 83 
J 0
(-5009 2464);
DISPLAY 0.638298 (-5009 2464);
PAINT MONO (-5009 2464);
FORCEPROP 2 LAST $XR18 84 
J 0
(-5099 2464);
DISPLAY 0.638298 (-5099 2464);
PAINT MONO (-5099 2464);
FORCEPROP 2 LAST $XR19 85 
J 0
(-4379 2536);
DISPLAY 0.638298 (-4379 2536);
PAINT MONO (-4379 2536);
FORCEPROP 2 LAST $XR20 86 
J 0
(-4469 2536);
DISPLAY 0.638298 (-4469 2536);
PAINT MONO (-4469 2536);
FORCEPROP 2 LAST $XR21 87 
J 0
(-4559 2536);
DISPLAY 0.638298 (-4559 2536);
PAINT MONO (-4559 2536);
FORCEPROP 2 LAST $XR22 88 
J 0
(-4649 2536);
DISPLAY 0.638298 (-4649 2536);
PAINT MONO (-4649 2536);
FORCEPROP 2 LAST $XR23 94 
J 0
(-4739 2536);
DISPLAY 0.638298 (-4739 2536);
PAINT MONO (-4739 2536);
FORCEPROP 2 LAST CDS_LIB mstr_standard
J 0
(-4125 2500);
DISPLAY 0.787234 (-4125 2500);
PAINT MONO (-4125 2500);
DISPLAY INVISIBLE (-4125 2500);
FORCEPROP 1 LAST OFFPAGE TRUE
J 0
(-3800 2375);
DISPLAY 1.404255 (-3800 2375);
PAINT GREEN (-3800 2375);
DISPLAY INVISIBLE (-3800 2375);
FORCEPROP 1 LAST COMMENT_BODY TRUE
J 0
(-4025 2425);
DISPLAY 1.404255 (-4025 2425);
PAINT GREEN (-4025 2425);
DISPLAY INVISIBLE (-4025 2425);
FORCEPROP 2 LAST PATH I173
J 0
(-4075 2575);
DISPLAY 0.787234 (-4075 2575);
PAINT ORANGE (-4075 2575);
DISPLAY INVISIBLE (-4075 2575);
FORCEADD CAP_A..1
R 2
(-4650 1500);
FORCEPROP 1 LAST LOCATION C6U17
J 2
(-4700 1600);
DISPLAY 0.617021 (-4700 1600);
PAINT AQUA (-4700 1600);
FORCEPROP 1 LAST PART_NUMBER A36096-045
J 2
(-4700 1350);
DISPLAY 0.617021 (-4700 1350);
PAINT BLUE (-4700 1350);
FORCEPROP 1 LAST VALUE 0.01UF
J 2
(-4700 1550);
DISPLAY 0.617021 (-4700 1550);
PAINT SKYBLUE (-4700 1550);
FORCEPROP 1 LAST TOLERANCE 10%
J 2
(-4700 1450);
DISPLAY 0.617021 (-4700 1450);
PAINT SKYBLUE (-4700 1450);
FORCEPROP 1 LAST PACK_TYPE 0402V
J 2
(-4700 1300);
DISPLAY 0.617021 (-4700 1300);
PAINT SKYBLUE (-4700 1300);
FORCEPROP 1 LAST VOLTAGE 25V
J 2
(-4700 1500);
DISPLAY 0.617021 (-4700 1500);
PAINT SKYBLUE (-4700 1500);
FORCEPROP 1 LAST MATERIAL X7R
J 2
(-4700 1400);
DISPLAY 0.617021 (-4700 1400);
PAINT SKYBLUE (-4700 1400);
FORCEPROP 1 LASTPIN (-4650 1600) $PN 1
J 2
(-4660 1580);
DISPLAY 0.617021 (-4660 1580);
PAINT ORANGE (-4660 1580);
FORCEPROP 1 LASTPIN (-4650 1400) $PN 2
J 2
(-4660 1380);
DISPLAY 0.617021 (-4660 1380);
PAINT ORANGE (-4660 1380);
FORCEPROP 2 LAST CDS_LOCATION C6U17
J 2
(-4700 1600);
DISPLAY 0.617021 (-4700 1600);
PAINT AQUA (-4700 1600);
DISPLAY INVISIBLE (-4700 1600);
FORCEPROP 2 LAST BOM_COST MEM
J 0
(-4650 1500);
PAINT ORANGE (-4650 1500);
DISPLAY INVISIBLE (-4650 1500);
FORCEPROP 2 LAST CDS_LIB dev_discrete
J 0
(-4650 1500);
PAINT ORANGE (-4650 1500);
DISPLAY INVISIBLE (-4650 1500);
FORCEPROP 2 LAST CDS_SEC 1
J 0
(-4700 1650);
PAINT ORANGE (-4700 1650);
DISPLAY INVISIBLE (-4700 1650);
FORCEPROP 2 LAST SEC_TYPE 0402V
J 0
(-4700 1700);
DISPLAY 1.021277 (-4700 1700);
PAINT ORANGE (-4700 1700);
DISPLAY INVISIBLE (-4700 1700);
FORCEPROP 2 LAST SEC 1
J 0
(-4700 1700);
PAINT MONO (-4700 1700);
DISPLAY INVISIBLE (-4700 1700);
FORCEPROP 1 LAST PATH I176
J 2
(-4700 1650);
DISPLAY 0.978723 (-4700 1650);
PAINT WHITE (-4700 1650);
DISPLAY INVISIBLE (-4700 1650);
FORCEPROP 2 LAST ROOM DDR4_CH_B
J 0
(-4650 1500);
PAINT ORANGE (-4650 1500);
DISPLAY INVISIBLE (-4650 1500);
FORCEADD GND..1
(-4650 1250);
FORCEPROP 3 LASTPIN (-4650 1300) SIG_NAME GND\g
J 0
(-4640 1310);
DISPLAY 0.659574 (-4640 1310);
PAINT MONO (-4640 1310);
DISPLAY INVISIBLE (-4640 1310);
FORCEPROP 1 LAST VOLTAGE 0
J 0
(-4650 1250);
PAINT SKYBLUE (-4650 1250);
DISPLAY INVISIBLE (-4650 1250);
FORCEPROP 1 LAST SIZE 1B
J 0
(-4575 1200);
DISPLAY 1.787234 (-4575 1200);
PAINT GREEN (-4575 1200);
DISPLAY INVISIBLE (-4575 1200);
FORCEPROP 2 LAST BOM_COST MEM
J 0
(-4650 1255);
PAINT ORANGE (-4650 1255);
DISPLAY INVISIBLE (-4650 1255);
FORCEPROP 2 LAST CDS_LIB mstr_symbols
J 0
(-4650 1250);
PAINT ORANGE (-4650 1250);
DISPLAY INVISIBLE (-4650 1250);
FORCEPROP 1 LAST BODY_TYPE PLUMBING
J 0
(-4695 1207);
DISPLAY 0.340426 (-4695 1207);
PAINT GREEN (-4695 1207);
DISPLAY INVISIBLE (-4695 1207);
FORCEPROP 1 LAST PATH I177
J 0
(-4575 1250);
DISPLAY 1.404255 (-4575 1250);
PAINT GREEN (-4575 1250);
DISPLAY INVISIBLE (-4575 1250);
FORCEPROP 2 LAST ROOM DDR4_CH_B
J 0
(-4650 1255);
PAINT ORANGE (-4650 1255);
DISPLAY INVISIBLE (-4650 1255);
FORCEPROP 1 LAST HDL_POWER GND
J 0
(-4650 1400);
DISPLAY 1.404255 (-4650 1400);
PAINT GREEN (-4650 1400);
DISPLAY INVISIBLE (-4650 1400);
FORCEADD PVPP_ABC..1
(-800 3000);
FORCEPROP 3 LASTPIN (-800 2950) SIG_NAME PVPP_ABC\g
J 0
(-790 2960);
DISPLAY 0.659574 (-790 2960);
PAINT MONO (-790 2960);
DISPLAY INVISIBLE (-790 2960);
FORCEPROP 1 LAST VOLTAGE 2.5V
J 0
(-845 2957);
DISPLAY 0.340426 (-845 2957);
PAINT SKYBLUE (-845 2957);
DISPLAY INVISIBLE (-845 2957);
FORCEPROP 2 LAST BOM_COST MEM
J 0
(-800 3005);
PAINT ORANGE (-800 3005);
DISPLAY INVISIBLE (-800 3005);
FORCEPROP 2 LAST CDS_LIB mstr_symbols
J 0
(-800 3000);
PAINT ORANGE (-800 3000);
DISPLAY INVISIBLE (-800 3000);
FORCEPROP 1 LAST BODY_TYPE PLUMBING
J 0
(-845 2957);
DISPLAY 0.340426 (-845 2957);
PAINT GREEN (-845 2957);
DISPLAY INVISIBLE (-845 2957);
FORCEPROP 1 LAST PATH I178
J 0
(-750 3025);
DISPLAY 0.872340 (-750 3025);
PAINT AQUA (-750 3025);
DISPLAY INVISIBLE (-750 3025);
FORCEPROP 2 LAST ROOM DDR4_CH_B
J 0
(-800 3005);
PAINT ORANGE (-800 3005);
DISPLAY INVISIBLE (-800 3005);
FORCEPROP 1 LAST HDL_POWER PVPP_ABC
J 1
(-800 3050);
DISPLAY 0.872340 (-800 3050);
PAINT GREEN (-800 3050);
DISPLAY INVISIBLE (-800 3050);
FORCEADD PVPP_ABC..1
(-4650 2250);
FORCEPROP 3 LASTPIN (-4650 2200) SIG_NAME PVPP_ABC\g
J 0
(-4640 2210);
DISPLAY 0.659574 (-4640 2210);
PAINT MONO (-4640 2210);
DISPLAY INVISIBLE (-4640 2210);
FORCEPROP 1 LAST VOLTAGE 2.5V
J 0
(-4695 2207);
DISPLAY 0.340426 (-4695 2207);
PAINT SKYBLUE (-4695 2207);
DISPLAY INVISIBLE (-4695 2207);
FORCEPROP 2 LAST BOM_COST MEM
J 0
(-4650 2255);
PAINT ORANGE (-4650 2255);
DISPLAY INVISIBLE (-4650 2255);
FORCEPROP 2 LAST CDS_LIB mstr_symbols
J 0
(-4650 2250);
PAINT ORANGE (-4650 2250);
DISPLAY INVISIBLE (-4650 2250);
FORCEPROP 1 LAST BODY_TYPE PLUMBING
J 0
(-4695 2207);
DISPLAY 0.340426 (-4695 2207);
PAINT GREEN (-4695 2207);
DISPLAY INVISIBLE (-4695 2207);
FORCEPROP 1 LAST PATH I179
J 0
(-4600 2275);
DISPLAY 0.872340 (-4600 2275);
PAINT AQUA (-4600 2275);
DISPLAY INVISIBLE (-4600 2275);
FORCEPROP 2 LAST ROOM DDR4_CH_B
J 0
(-4650 2255);
PAINT ORANGE (-4650 2255);
DISPLAY INVISIBLE (-4650 2255);
FORCEPROP 1 LAST HDL_POWER PVPP_ABC
J 1
(-4650 2300);
DISPLAY 0.872340 (-4650 2300);
PAINT GREEN (-4650 2300);
DISPLAY INVISIBLE (-4650 2300);
FORCEADD TAP..6
R 2
(700 4550);
FORCEPROP 3 LASTPIN (650 4550) SIG_NAME M_C_DQS_DP<11>
J 0
(660 4560);
DISPLAY 0.659574 (660 4560);
PAINT MONO (660 4560);
DISPLAY INVISIBLE (660 4560);
FORCEPROP 1 LASTPIN (650 4550) BN 11
J 2
(700 4560);
DISPLAY 0.617021 (700 4560);
PAINT PINK (700 4560);
FORCEPROP 2 LAST CDS_LIB mstr_standard
J 0
(700 4550);
DISPLAY 0.787234 (700 4550);
PAINT MONO (700 4550);
DISPLAY INVISIBLE (700 4550);
FORCEPROP 1 LAST BODY_TYPE PLUMBING
J 2
(700 4500);
DISPLAY 1.234043 (700 4500);
PAINT GREEN (700 4500);
DISPLAY INVISIBLE (700 4500);
FORCEPROP 1 LAST HDL_TAP TRUE
J 2
(375 4425);
DISPLAY 1.234043 (375 4425);
PAINT WHITE (375 4425);
DISPLAY INVISIBLE (375 4425);
FORCEPROP 1 LAST PATH I18
J 2
(700 4550);
DISPLAY 0.936170 (700 4550);
PAINT GREEN (700 4550);
DISPLAY INVISIBLE (700 4550);
FORCEADD OFFPAGE..1
(-3800 1400);
FORCEPROP 2 LAST $XR0 89 
J 0
(-4051 1400);
DISPLAY 0.638298 (-4051 1400);
PAINT MONO (-4051 1400);
FORCEPROP 2 LAST $XR1 43 
J 0
(-4141 1400);
DISPLAY 0.638298 (-4141 1400);
PAINT MONO (-4141 1400);
FORCEPROP 2 LAST $XR2 44 
J 0
(-4231 1400);
DISPLAY 0.638298 (-4231 1400);
PAINT MONO (-4231 1400);
FORCEPROP 2 LAST $XR3 45 
J 0
(-4321 1400);
DISPLAY 0.638298 (-4321 1400);
PAINT MONO (-4321 1400);
FORCEPROP 2 LAST $XR4 46 
J 0
(-4411 1400);
DISPLAY 0.638298 (-4411 1400);
PAINT MONO (-4411 1400);
FORCEPROP 2 LAST $XR5 47 
J 0
(-4501 1400);
DISPLAY 0.638298 (-4501 1400);
PAINT MONO (-4501 1400);
FORCEPROP 2 LAST CDS_LIB mstr_standard
J 0
(-3800 1400);
PAINT ORANGE (-3800 1400);
DISPLAY INVISIBLE (-3800 1400);
FORCEPROP 1 LAST OFFPAGE TRUE
J 0
(-3475 1275);
DISPLAY 0.936170 (-3475 1275);
PAINT GREEN (-3475 1275);
DISPLAY INVISIBLE (-3475 1275);
FORCEPROP 1 LAST COMMENT_BODY TRUE
J 0
(-3675 1300);
DISPLAY 0.936170 (-3675 1300);
PAINT GREEN (-3675 1300);
DISPLAY INVISIBLE (-3675 1300);
FORCEPROP 2 LAST PATH I180
J 0
(-3750 1475);
PAINT ORANGE (-3750 1475);
DISPLAY INVISIBLE (-3750 1475);
FORCEADD GND..1
(-4650 1850);
FORCEPROP 3 LASTPIN (-4650 1900) SIG_NAME GND\g
J 0
(-4640 1910);
DISPLAY 0.659574 (-4640 1910);
PAINT MONO (-4640 1910);
DISPLAY INVISIBLE (-4640 1910);
FORCEPROP 1 LAST VOLTAGE 0
J 0
(-4650 1850);
PAINT SKYBLUE (-4650 1850);
DISPLAY INVISIBLE (-4650 1850);
FORCEPROP 2 LAST CDS_LIB mstr_symbols
J 0
(-4650 1850);
PAINT ORANGE (-4650 1850);
DISPLAY INVISIBLE (-4650 1850);
FORCEPROP 2 LAST BOM_COST MEM
J 0
(-4650 1855);
PAINT ORANGE (-4650 1855);
DISPLAY INVISIBLE (-4650 1855);
FORCEPROP 1 LAST SIZE 1B
J 0
(-4575 1800);
DISPLAY 1.787234 (-4575 1800);
PAINT GREEN (-4575 1800);
DISPLAY INVISIBLE (-4575 1800);
FORCEPROP 1 LAST BODY_TYPE PLUMBING
J 0
(-4695 1807);
DISPLAY 0.340426 (-4695 1807);
PAINT GREEN (-4695 1807);
DISPLAY INVISIBLE (-4695 1807);
FORCEPROP 1 LAST PATH I184
J 0
(-4575 1850);
DISPLAY 0.872340 (-4575 1850);
PAINT AQUA (-4575 1850);
DISPLAY INVISIBLE (-4575 1850);
FORCEPROP 2 LAST ROOM DDR4_CH_B
J 0
(-4650 1855);
PAINT ORANGE (-4650 1855);
DISPLAY INVISIBLE (-4650 1855);
FORCEPROP 1 LAST HDL_POWER GND
J 0
(-4650 2000);
DISPLAY 1.404255 (-4650 2000);
PAINT GREEN (-4650 2000);
DISPLAY INVISIBLE (-4650 2000);
FORCEADD P12V_NVDIMM_ABC..1
(600 3075);
FORCEPROP 3 LASTPIN (600 3025) SIG_NAME P12V_NVDIMM_ABC\g
J 0
(610 3035);
DISPLAY 0.659574 (610 3035);
PAINT MONO (610 3035);
DISPLAY INVISIBLE (610 3035);
FORCEPROP 1 LAST VOLTAGE 12.0
J 0
(555 3032);
DISPLAY 0.340426 (555 3032);
PAINT SKYBLUE (555 3032);
DISPLAY INVISIBLE (555 3032);
FORCEPROP 2 LAST CDS_LIB mstr_symbols
J 0
(600 3075);
PAINT ORANGE (600 3075);
DISPLAY INVISIBLE (600 3075);
FORCEPROP 1 LAST BODY_TYPE PLUMBING
J 0
(555 3032);
DISPLAY 0.340426 (555 3032);
PAINT GREEN (555 3032);
DISPLAY INVISIBLE (555 3032);
FORCEPROP 1 LAST PATH I185
J 0
(650 3100);
DISPLAY 0.872340 (650 3100);
PAINT AQUA (650 3100);
DISPLAY INVISIBLE (650 3100);
FORCEPROP 1 LAST HDL_POWER P12V_NVDIMM_ABC
J 1
(600 3100);
DISPLAY 0.872340 (600 3100);
PAINT GREEN (600 3100);
DISPLAY INVISIBLE (600 3100);
FORCEADD TAP..6
R 2
(900 4400);
FORCEPROP 3 LASTPIN (850 4400) SIG_NAME M_C_DQS_DN<10>
J 0
(860 4410);
DISPLAY 0.659574 (860 4410);
PAINT MONO (860 4410);
DISPLAY INVISIBLE (860 4410);
FORCEPROP 1 LASTPIN (850 4400) BN 10
J 2
(900 4410);
DISPLAY 0.617021 (900 4410);
PAINT PINK (900 4410);
FORCEPROP 2 LAST CDS_LIB mstr_standard
J 0
(900 4400);
DISPLAY 0.787234 (900 4400);
PAINT MONO (900 4400);
DISPLAY INVISIBLE (900 4400);
FORCEPROP 1 LAST BODY_TYPE PLUMBING
J 2
(900 4350);
DISPLAY 1.234043 (900 4350);
PAINT GREEN (900 4350);
DISPLAY INVISIBLE (900 4350);
FORCEPROP 1 LAST HDL_TAP TRUE
J 2
(575 4275);
DISPLAY 1.234043 (575 4275);
PAINT GREEN (575 4275);
DISPLAY INVISIBLE (575 4275);
FORCEPROP 1 LAST PATH I19
J 2
(900 4400);
DISPLAY 0.936170 (900 4400);
PAINT GREEN (900 4400);
DISPLAY INVISIBLE (900 4400);
FORCEADD OFFPAGE..3
(1600 5150);
FORCEPROP 2 LAST $XR0 25 
J 0
(1814 5150);
DISPLAY 0.638298 (1814 5150);
PAINT MONO (1814 5150);
FORCEPROP 2 LAST $XR1 47 
J 0
(1904 5150);
DISPLAY 0.638298 (1904 5150);
PAINT MONO (1904 5150);
FORCEPROP 2 LAST CDS_LIB mstr_standard
J 0
(1600 5150);
DISPLAY 0.787234 (1600 5150);
PAINT MONO (1600 5150);
DISPLAY INVISIBLE (1600 5150);
FORCEPROP 1 LAST OFFPAGE TRUE
J 0
(1925 5025);
DISPLAY 0.936170 (1925 5025);
PAINT GREEN (1925 5025);
DISPLAY INVISIBLE (1925 5025);
FORCEPROP 1 LAST COMMENT_BODY TRUE
J 0
(1550 5050);
DISPLAY 0.936170 (1550 5050);
PAINT GREEN (1550 5050);
DISPLAY INVISIBLE (1550 5050);
FORCEPROP 2 LAST PATH I2
J 0
(1800 5225);
DISPLAY 0.787234 (1800 5225);
PAINT MONO (1800 5225);
DISPLAY INVISIBLE (1800 5225);
FORCEADD TAP..6
R 2
(900 4500);
FORCEPROP 3 LASTPIN (850 4500) SIG_NAME M_C_DQS_DN<11>
J 0
(860 4510);
DISPLAY 0.659574 (860 4510);
PAINT MONO (860 4510);
DISPLAY INVISIBLE (860 4510);
FORCEPROP 1 LASTPIN (850 4500) BN 11
J 2
(900 4510);
DISPLAY 0.617021 (900 4510);
PAINT PINK (900 4510);
FORCEPROP 2 LAST CDS_LIB mstr_standard
J 0
(900 4500);
DISPLAY 0.787234 (900 4500);
PAINT MONO (900 4500);
DISPLAY INVISIBLE (900 4500);
FORCEPROP 1 LAST BODY_TYPE PLUMBING
J 2
(900 4450);
DISPLAY 1.234043 (900 4450);
PAINT GREEN (900 4450);
DISPLAY INVISIBLE (900 4450);
FORCEPROP 1 LAST HDL_TAP TRUE
J 2
(575 4375);
DISPLAY 1.234043 (575 4375);
PAINT GREEN (575 4375);
DISPLAY INVISIBLE (575 4375);
FORCEPROP 1 LAST PATH I20
J 2
(900 4500);
DISPLAY 0.936170 (900 4500);
PAINT GREEN (900 4500);
DISPLAY INVISIBLE (900 4500);
FORCEADD TAP..6
R 2
(900 4300);
FORCEPROP 3 LASTPIN (850 4300) SIG_NAME M_C_DQS_DN<9>
J 0
(860 4310);
DISPLAY 0.659574 (860 4310);
PAINT MONO (860 4310);
DISPLAY INVISIBLE (860 4310);
FORCEPROP 1 LASTPIN (850 4300) BN 9
J 2
(900 4310);
DISPLAY 0.617021 (900 4310);
PAINT PINK (900 4310);
FORCEPROP 2 LAST CDS_LIB mstr_standard
J 0
(900 4300);
DISPLAY 0.787234 (900 4300);
PAINT MONO (900 4300);
DISPLAY INVISIBLE (900 4300);
FORCEPROP 1 LAST BODY_TYPE PLUMBING
J 2
(900 4250);
DISPLAY 1.234043 (900 4250);
PAINT GREEN (900 4250);
DISPLAY INVISIBLE (900 4250);
FORCEPROP 1 LAST HDL_TAP TRUE
J 2
(575 4175);
DISPLAY 1.234043 (575 4175);
PAINT GREEN (575 4175);
DISPLAY INVISIBLE (575 4175);
FORCEPROP 1 LAST PATH I21
J 2
(900 4300);
DISPLAY 0.936170 (900 4300);
PAINT GREEN (900 4300);
DISPLAY INVISIBLE (900 4300);
FORCEADD TAP..6
R 2
(700 4450);
FORCEPROP 3 LASTPIN (650 4450) SIG_NAME M_C_DQS_DP<10>
J 0
(660 4460);
DISPLAY 0.659574 (660 4460);
PAINT MONO (660 4460);
DISPLAY INVISIBLE (660 4460);
FORCEPROP 1 LASTPIN (650 4450) BN 10
J 2
(700 4460);
DISPLAY 0.617021 (700 4460);
PAINT PINK (700 4460);
FORCEPROP 2 LAST CDS_LIB mstr_standard
J 0
(700 4450);
DISPLAY 0.787234 (700 4450);
PAINT MONO (700 4450);
DISPLAY INVISIBLE (700 4450);
FORCEPROP 1 LAST BODY_TYPE PLUMBING
J 2
(700 4400);
DISPLAY 1.234043 (700 4400);
PAINT GREEN (700 4400);
DISPLAY INVISIBLE (700 4400);
FORCEPROP 1 LAST HDL_TAP TRUE
J 2
(375 4325);
DISPLAY 1.234043 (375 4325);
PAINT WHITE (375 4325);
DISPLAY INVISIBLE (375 4325);
FORCEPROP 1 LAST PATH I22
J 2
(700 4450);
DISPLAY 0.936170 (700 4450);
PAINT GREEN (700 4450);
DISPLAY INVISIBLE (700 4450);
FORCEADD TAP..6
R 2
(700 4350);
FORCEPROP 3 LASTPIN (650 4350) SIG_NAME M_C_DQS_DP<9>
J 0
(660 4360);
DISPLAY 0.659574 (660 4360);
PAINT MONO (660 4360);
DISPLAY INVISIBLE (660 4360);
FORCEPROP 1 LASTPIN (650 4350) BN 9
J 2
(700 4360);
DISPLAY 0.617021 (700 4360);
PAINT PINK (700 4360);
FORCEPROP 2 LAST CDS_LIB mstr_standard
J 0
(700 4350);
DISPLAY 0.787234 (700 4350);
PAINT MONO (700 4350);
DISPLAY INVISIBLE (700 4350);
FORCEPROP 1 LAST BODY_TYPE PLUMBING
J 2
(700 4300);
DISPLAY 1.234043 (700 4300);
PAINT GREEN (700 4300);
DISPLAY INVISIBLE (700 4300);
FORCEPROP 1 LAST HDL_TAP TRUE
J 2
(375 4225);
DISPLAY 1.234043 (375 4225);
PAINT WHITE (375 4225);
DISPLAY INVISIBLE (375 4225);
FORCEPROP 1 LAST PATH I23
J 2
(700 4350);
DISPLAY 0.936170 (700 4350);
PAINT GREEN (700 4350);
DISPLAY INVISIBLE (700 4350);
FORCEADD TAP..6
R 2
(900 4100);
FORCEPROP 3 LASTPIN (850 4100) SIG_NAME M_C_DQS_DN<7>
J 0
(860 4110);
DISPLAY 0.659574 (860 4110);
PAINT MONO (860 4110);
DISPLAY INVISIBLE (860 4110);
FORCEPROP 1 LASTPIN (850 4100) BN 7
J 2
(900 4110);
DISPLAY 0.617021 (900 4110);
PAINT PINK (900 4110);
FORCEPROP 2 LAST CDS_LIB mstr_standard
J 0
(900 4100);
DISPLAY 0.787234 (900 4100);
PAINT MONO (900 4100);
DISPLAY INVISIBLE (900 4100);
FORCEPROP 1 LAST BODY_TYPE PLUMBING
J 2
(900 4050);
DISPLAY 1.234043 (900 4050);
PAINT GREEN (900 4050);
DISPLAY INVISIBLE (900 4050);
FORCEPROP 1 LAST HDL_TAP TRUE
J 2
(575 3975);
DISPLAY 1.234043 (575 3975);
PAINT GREEN (575 3975);
DISPLAY INVISIBLE (575 3975);
FORCEPROP 1 LAST PATH I24
J 2
(900 4100);
DISPLAY 0.936170 (900 4100);
PAINT GREEN (900 4100);
DISPLAY INVISIBLE (900 4100);
FORCEADD TAP..6
R 2
(900 4200);
FORCEPROP 3 LASTPIN (850 4200) SIG_NAME M_C_DQS_DN<8>
J 0
(860 4210);
DISPLAY 0.659574 (860 4210);
PAINT MONO (860 4210);
DISPLAY INVISIBLE (860 4210);
FORCEPROP 1 LASTPIN (850 4200) BN 8
J 2
(900 4210);
DISPLAY 0.617021 (900 4210);
PAINT PINK (900 4210);
FORCEPROP 2 LAST CDS_LIB mstr_standard
J 0
(900 4200);
DISPLAY 0.787234 (900 4200);
PAINT MONO (900 4200);
DISPLAY INVISIBLE (900 4200);
FORCEPROP 1 LAST BODY_TYPE PLUMBING
J 2
(900 4150);
DISPLAY 1.234043 (900 4150);
PAINT GREEN (900 4150);
DISPLAY INVISIBLE (900 4150);
FORCEPROP 1 LAST HDL_TAP TRUE
J 2
(575 4075);
DISPLAY 1.234043 (575 4075);
PAINT GREEN (575 4075);
DISPLAY INVISIBLE (575 4075);
FORCEPROP 1 LAST PATH I25
J 2
(900 4200);
DISPLAY 0.936170 (900 4200);
PAINT GREEN (900 4200);
DISPLAY INVISIBLE (900 4200);
FORCEADD TAP..6
R 2
(700 4250);
FORCEPROP 3 LASTPIN (650 4250) SIG_NAME M_C_DQS_DP<8>
J 0
(660 4260);
DISPLAY 0.659574 (660 4260);
PAINT MONO (660 4260);
DISPLAY INVISIBLE (660 4260);
FORCEPROP 1 LASTPIN (650 4250) BN 8
J 2
(700 4260);
DISPLAY 0.617021 (700 4260);
PAINT PINK (700 4260);
FORCEPROP 2 LAST CDS_LIB mstr_standard
J 0
(700 4250);
DISPLAY 0.787234 (700 4250);
PAINT MONO (700 4250);
DISPLAY INVISIBLE (700 4250);
FORCEPROP 1 LAST BODY_TYPE PLUMBING
J 2
(700 4200);
DISPLAY 1.234043 (700 4200);
PAINT GREEN (700 4200);
DISPLAY INVISIBLE (700 4200);
FORCEPROP 1 LAST HDL_TAP TRUE
J 2
(375 4125);
DISPLAY 1.234043 (375 4125);
PAINT WHITE (375 4125);
DISPLAY INVISIBLE (375 4125);
FORCEPROP 1 LAST PATH I26
J 2
(700 4250);
DISPLAY 0.936170 (700 4250);
PAINT GREEN (700 4250);
DISPLAY INVISIBLE (700 4250);
FORCEADD TAP..6
R 2
(700 4150);
FORCEPROP 3 LASTPIN (650 4150) SIG_NAME M_C_DQS_DP<7>
J 0
(660 4160);
DISPLAY 0.659574 (660 4160);
PAINT MONO (660 4160);
DISPLAY INVISIBLE (660 4160);
FORCEPROP 1 LASTPIN (650 4150) BN 7
J 2
(700 4160);
DISPLAY 0.617021 (700 4160);
PAINT PINK (700 4160);
FORCEPROP 2 LAST CDS_LIB mstr_standard
J 0
(700 4150);
DISPLAY 0.787234 (700 4150);
PAINT MONO (700 4150);
DISPLAY INVISIBLE (700 4150);
FORCEPROP 1 LAST BODY_TYPE PLUMBING
J 2
(700 4100);
DISPLAY 1.234043 (700 4100);
PAINT GREEN (700 4100);
DISPLAY INVISIBLE (700 4100);
FORCEPROP 1 LAST HDL_TAP TRUE
J 2
(375 4025);
DISPLAY 1.234043 (375 4025);
PAINT WHITE (375 4025);
DISPLAY INVISIBLE (375 4025);
FORCEPROP 1 LAST PATH I27
J 2
(700 4150);
DISPLAY 0.936170 (700 4150);
PAINT GREEN (700 4150);
DISPLAY INVISIBLE (700 4150);
FORCEADD TAP..6
R 2
(700 4050);
FORCEPROP 3 LASTPIN (650 4050) SIG_NAME M_C_DQS_DP<6>
J 0
(660 4060);
DISPLAY 0.659574 (660 4060);
PAINT MONO (660 4060);
DISPLAY INVISIBLE (660 4060);
FORCEPROP 1 LASTPIN (650 4050) BN 6
J 2
(700 4060);
DISPLAY 0.617021 (700 4060);
PAINT PINK (700 4060);
FORCEPROP 2 LAST CDS_LIB mstr_standard
J 0
(700 4050);
DISPLAY 0.787234 (700 4050);
PAINT MONO (700 4050);
DISPLAY INVISIBLE (700 4050);
FORCEPROP 1 LAST BODY_TYPE PLUMBING
J 2
(700 4000);
DISPLAY 1.234043 (700 4000);
PAINT GREEN (700 4000);
DISPLAY INVISIBLE (700 4000);
FORCEPROP 1 LAST HDL_TAP TRUE
J 2
(375 3925);
DISPLAY 1.234043 (375 3925);
PAINT WHITE (375 3925);
DISPLAY INVISIBLE (375 3925);
FORCEPROP 1 LAST PATH I28
J 2
(700 4050);
DISPLAY 0.936170 (700 4050);
PAINT GREEN (700 4050);
DISPLAY INVISIBLE (700 4050);
FORCEADD TAP..6
R 2
(900 3900);
FORCEPROP 3 LASTPIN (850 3900) SIG_NAME M_C_DQS_DN<5>
J 0
(860 3910);
DISPLAY 0.659574 (860 3910);
PAINT MONO (860 3910);
DISPLAY INVISIBLE (860 3910);
FORCEPROP 1 LASTPIN (850 3900) BN 5
J 2
(900 3910);
DISPLAY 0.617021 (900 3910);
PAINT PINK (900 3910);
FORCEPROP 2 LAST CDS_LIB mstr_standard
J 0
(900 3900);
DISPLAY 0.787234 (900 3900);
PAINT MONO (900 3900);
DISPLAY INVISIBLE (900 3900);
FORCEPROP 1 LAST BODY_TYPE PLUMBING
J 2
(900 3850);
DISPLAY 1.234043 (900 3850);
PAINT GREEN (900 3850);
DISPLAY INVISIBLE (900 3850);
FORCEPROP 1 LAST HDL_TAP TRUE
J 2
(575 3775);
DISPLAY 1.234043 (575 3775);
PAINT GREEN (575 3775);
DISPLAY INVISIBLE (575 3775);
FORCEPROP 1 LAST PATH I29
J 2
(900 3900);
DISPLAY 0.936170 (900 3900);
PAINT GREEN (900 3900);
DISPLAY INVISIBLE (900 3900);
FORCEADD TAP..6
R 2
(900 5100);
FORCEPROP 3 LASTPIN (850 5100) SIG_NAME M_C_DQS_DN<17>
J 0
(860 5110);
DISPLAY 0.659574 (860 5110);
PAINT MONO (860 5110);
DISPLAY INVISIBLE (860 5110);
FORCEPROP 1 LASTPIN (850 5100) BN 17
J 2
(900 5110);
DISPLAY 0.617021 (900 5110);
PAINT PINK (900 5110);
FORCEPROP 2 LAST CDS_LIB mstr_standard
J 2
(900 5100);
DISPLAY 0.787234 (900 5100);
PAINT MONO (900 5100);
DISPLAY INVISIBLE (900 5100);
FORCEPROP 1 LAST BODY_TYPE PLUMBING
J 2
(900 5050);
DISPLAY 1.234043 (900 5050);
PAINT GREEN (900 5050);
DISPLAY INVISIBLE (900 5050);
FORCEPROP 1 LAST HDL_TAP TRUE
J 2
(575 4975);
DISPLAY 1.234043 (575 4975);
PAINT GREEN (575 4975);
DISPLAY INVISIBLE (575 4975);
FORCEPROP 1 LAST PATH I3
J 2
(900 5100);
DISPLAY 0.936170 (900 5100);
PAINT GREEN (900 5100);
DISPLAY INVISIBLE (900 5100);
FORCEADD TAP..6
R 2
(900 4000);
FORCEPROP 3 LASTPIN (850 4000) SIG_NAME M_C_DQS_DN<6>
J 0
(860 4010);
DISPLAY 0.659574 (860 4010);
PAINT MONO (860 4010);
DISPLAY INVISIBLE (860 4010);
FORCEPROP 1 LASTPIN (850 4000) BN 6
J 2
(900 4010);
DISPLAY 0.617021 (900 4010);
PAINT PINK (900 4010);
FORCEPROP 2 LAST CDS_LIB mstr_standard
J 0
(900 4000);
DISPLAY 0.787234 (900 4000);
PAINT MONO (900 4000);
DISPLAY INVISIBLE (900 4000);
FORCEPROP 1 LAST BODY_TYPE PLUMBING
J 2
(900 3950);
DISPLAY 1.234043 (900 3950);
PAINT GREEN (900 3950);
DISPLAY INVISIBLE (900 3950);
FORCEPROP 1 LAST HDL_TAP TRUE
J 2
(575 3875);
DISPLAY 1.234043 (575 3875);
PAINT GREEN (575 3875);
DISPLAY INVISIBLE (575 3875);
FORCEPROP 1 LAST PATH I30
J 2
(900 4000);
DISPLAY 0.936170 (900 4000);
PAINT GREEN (900 4000);
DISPLAY INVISIBLE (900 4000);
FORCEADD TAP..6
R 2
(900 3800);
FORCEPROP 3 LASTPIN (850 3800) SIG_NAME M_C_DQS_DN<4>
J 0
(860 3810);
DISPLAY 0.659574 (860 3810);
PAINT MONO (860 3810);
DISPLAY INVISIBLE (860 3810);
FORCEPROP 1 LASTPIN (850 3800) BN 4
J 2
(900 3810);
DISPLAY 0.617021 (900 3810);
PAINT PINK (900 3810);
FORCEPROP 2 LAST CDS_LIB mstr_standard
J 0
(900 3800);
DISPLAY 0.787234 (900 3800);
PAINT MONO (900 3800);
DISPLAY INVISIBLE (900 3800);
FORCEPROP 1 LAST BODY_TYPE PLUMBING
J 2
(900 3750);
DISPLAY 1.234043 (900 3750);
PAINT GREEN (900 3750);
DISPLAY INVISIBLE (900 3750);
FORCEPROP 1 LAST HDL_TAP TRUE
J 2
(575 3675);
DISPLAY 1.234043 (575 3675);
PAINT GREEN (575 3675);
DISPLAY INVISIBLE (575 3675);
FORCEPROP 1 LAST PATH I31
J 2
(900 3800);
DISPLAY 0.936170 (900 3800);
PAINT GREEN (900 3800);
DISPLAY INVISIBLE (900 3800);
FORCEADD TAP..6
R 2
(700 3950);
FORCEPROP 3 LASTPIN (650 3950) SIG_NAME M_C_DQS_DP<5>
J 0
(660 3960);
DISPLAY 0.659574 (660 3960);
PAINT MONO (660 3960);
DISPLAY INVISIBLE (660 3960);
FORCEPROP 1 LASTPIN (650 3950) BN 5
J 2
(700 3960);
DISPLAY 0.617021 (700 3960);
PAINT PINK (700 3960);
FORCEPROP 2 LAST CDS_LIB mstr_standard
J 0
(700 3950);
DISPLAY 0.787234 (700 3950);
PAINT MONO (700 3950);
DISPLAY INVISIBLE (700 3950);
FORCEPROP 1 LAST BODY_TYPE PLUMBING
J 2
(700 3900);
DISPLAY 1.234043 (700 3900);
PAINT GREEN (700 3900);
DISPLAY INVISIBLE (700 3900);
FORCEPROP 1 LAST HDL_TAP TRUE
J 2
(375 3825);
DISPLAY 1.234043 (375 3825);
PAINT WHITE (375 3825);
DISPLAY INVISIBLE (375 3825);
FORCEPROP 1 LAST PATH I32
J 2
(700 3950);
DISPLAY 0.936170 (700 3950);
PAINT GREEN (700 3950);
DISPLAY INVISIBLE (700 3950);
FORCEADD TAP..6
R 2
(700 3850);
FORCEPROP 3 LASTPIN (650 3850) SIG_NAME M_C_DQS_DP<4>
J 0
(660 3860);
DISPLAY 0.659574 (660 3860);
PAINT MONO (660 3860);
DISPLAY INVISIBLE (660 3860);
FORCEPROP 1 LASTPIN (650 3850) BN 4
J 2
(700 3860);
DISPLAY 0.617021 (700 3860);
PAINT PINK (700 3860);
FORCEPROP 2 LAST CDS_LIB mstr_standard
J 0
(700 3850);
DISPLAY 0.787234 (700 3850);
PAINT MONO (700 3850);
DISPLAY INVISIBLE (700 3850);
FORCEPROP 1 LAST BODY_TYPE PLUMBING
J 2
(700 3800);
DISPLAY 1.234043 (700 3800);
PAINT GREEN (700 3800);
DISPLAY INVISIBLE (700 3800);
FORCEPROP 1 LAST HDL_TAP TRUE
J 2
(375 3725);
DISPLAY 1.234043 (375 3725);
PAINT WHITE (375 3725);
DISPLAY INVISIBLE (375 3725);
FORCEPROP 1 LAST PATH I33
J 2
(700 3850);
DISPLAY 0.936170 (700 3850);
PAINT GREEN (700 3850);
DISPLAY INVISIBLE (700 3850);
FORCEADD TAP..6
R 2
(700 3750);
FORCEPROP 3 LASTPIN (650 3750) SIG_NAME M_C_DQS_DP<3>
J 0
(660 3760);
DISPLAY 0.659574 (660 3760);
PAINT MONO (660 3760);
DISPLAY INVISIBLE (660 3760);
FORCEPROP 1 LASTPIN (650 3750) BN 3
J 2
(700 3760);
DISPLAY 0.617021 (700 3760);
PAINT PINK (700 3760);
FORCEPROP 2 LAST CDS_LIB mstr_standard
J 0
(700 3750);
DISPLAY 0.787234 (700 3750);
PAINT MONO (700 3750);
DISPLAY INVISIBLE (700 3750);
FORCEPROP 1 LAST BODY_TYPE PLUMBING
J 2
(700 3700);
DISPLAY 1.234043 (700 3700);
PAINT GREEN (700 3700);
DISPLAY INVISIBLE (700 3700);
FORCEPROP 1 LAST HDL_TAP TRUE
J 2
(375 3625);
DISPLAY 1.234043 (375 3625);
PAINT WHITE (375 3625);
DISPLAY INVISIBLE (375 3625);
FORCEPROP 1 LAST PATH I34
J 2
(700 3750);
DISPLAY 0.936170 (700 3750);
PAINT GREEN (700 3750);
DISPLAY INVISIBLE (700 3750);
FORCEADD TAP..6
R 2
(900 3500);
FORCEPROP 3 LASTPIN (850 3500) SIG_NAME M_C_DQS_DN<1>
J 0
(860 3510);
DISPLAY 0.659574 (860 3510);
PAINT MONO (860 3510);
DISPLAY INVISIBLE (860 3510);
FORCEPROP 1 LASTPIN (850 3500) BN 1
J 2
(900 3510);
DISPLAY 0.617021 (900 3510);
PAINT PINK (900 3510);
FORCEPROP 2 LAST CDS_LIB mstr_standard
J 0
(900 3500);
DISPLAY 0.787234 (900 3500);
PAINT MONO (900 3500);
DISPLAY INVISIBLE (900 3500);
FORCEPROP 1 LAST BODY_TYPE PLUMBING
J 2
(900 3450);
DISPLAY 1.234043 (900 3450);
PAINT GREEN (900 3450);
DISPLAY INVISIBLE (900 3450);
FORCEPROP 1 LAST HDL_TAP TRUE
J 2
(575 3375);
DISPLAY 1.234043 (575 3375);
PAINT GREEN (575 3375);
DISPLAY INVISIBLE (575 3375);
FORCEPROP 1 LAST PATH I35
J 2
(900 3500);
DISPLAY 0.936170 (900 3500);
PAINT GREEN (900 3500);
DISPLAY INVISIBLE (900 3500);
FORCEADD TAP..6
R 2
(900 3600);
FORCEPROP 3 LASTPIN (850 3600) SIG_NAME M_C_DQS_DN<2>
J 0
(860 3610);
DISPLAY 0.659574 (860 3610);
PAINT MONO (860 3610);
DISPLAY INVISIBLE (860 3610);
FORCEPROP 1 LASTPIN (850 3600) BN 2
J 2
(900 3610);
DISPLAY 0.617021 (900 3610);
PAINT PINK (900 3610);
FORCEPROP 2 LAST CDS_LIB mstr_standard
J 0
(900 3600);
DISPLAY 0.787234 (900 3600);
PAINT MONO (900 3600);
DISPLAY INVISIBLE (900 3600);
FORCEPROP 1 LAST BODY_TYPE PLUMBING
J 2
(900 3550);
DISPLAY 1.234043 (900 3550);
PAINT GREEN (900 3550);
DISPLAY INVISIBLE (900 3550);
FORCEPROP 1 LAST HDL_TAP TRUE
J 2
(575 3475);
DISPLAY 1.234043 (575 3475);
PAINT GREEN (575 3475);
DISPLAY INVISIBLE (575 3475);
FORCEPROP 1 LAST PATH I36
J 2
(900 3600);
DISPLAY 0.936170 (900 3600);
PAINT GREEN (900 3600);
DISPLAY INVISIBLE (900 3600);
FORCEADD TAP..6
R 2
(900 3700);
FORCEPROP 3 LASTPIN (850 3700) SIG_NAME M_C_DQS_DN<3>
J 0
(860 3710);
DISPLAY 0.659574 (860 3710);
PAINT MONO (860 3710);
DISPLAY INVISIBLE (860 3710);
FORCEPROP 1 LASTPIN (850 3700) BN 3
J 2
(900 3710);
DISPLAY 0.617021 (900 3710);
PAINT PINK (900 3710);
FORCEPROP 2 LAST CDS_LIB mstr_standard
J 0
(900 3700);
DISPLAY 0.787234 (900 3700);
PAINT MONO (900 3700);
DISPLAY INVISIBLE (900 3700);
FORCEPROP 1 LAST BODY_TYPE PLUMBING
J 2
(900 3650);
DISPLAY 1.234043 (900 3650);
PAINT GREEN (900 3650);
DISPLAY INVISIBLE (900 3650);
FORCEPROP 1 LAST HDL_TAP TRUE
J 2
(575 3575);
DISPLAY 1.234043 (575 3575);
PAINT GREEN (575 3575);
DISPLAY INVISIBLE (575 3575);
FORCEPROP 1 LAST PATH I37
J 2
(900 3700);
DISPLAY 0.936170 (900 3700);
PAINT GREEN (900 3700);
DISPLAY INVISIBLE (900 3700);
FORCEADD TAP..6
R 2
(700 3650);
FORCEPROP 3 LASTPIN (650 3650) SIG_NAME M_C_DQS_DP<2>
J 0
(660 3660);
DISPLAY 0.659574 (660 3660);
PAINT MONO (660 3660);
DISPLAY INVISIBLE (660 3660);
FORCEPROP 1 LASTPIN (650 3650) BN 2
J 2
(700 3660);
DISPLAY 0.617021 (700 3660);
PAINT PINK (700 3660);
FORCEPROP 2 LAST CDS_LIB mstr_standard
J 0
(700 3650);
DISPLAY 0.787234 (700 3650);
PAINT MONO (700 3650);
DISPLAY INVISIBLE (700 3650);
FORCEPROP 1 LAST BODY_TYPE PLUMBING
J 2
(700 3600);
DISPLAY 1.234043 (700 3600);
PAINT GREEN (700 3600);
DISPLAY INVISIBLE (700 3600);
FORCEPROP 1 LAST HDL_TAP TRUE
J 2
(375 3525);
DISPLAY 1.234043 (375 3525);
PAINT WHITE (375 3525);
DISPLAY INVISIBLE (375 3525);
FORCEPROP 1 LAST PATH I38
J 2
(700 3650);
DISPLAY 0.936170 (700 3650);
PAINT GREEN (700 3650);
DISPLAY INVISIBLE (700 3650);
FORCEADD TAP..6
R 2
(700 3550);
FORCEPROP 3 LASTPIN (650 3550) SIG_NAME M_C_DQS_DP<1>
J 0
(660 3560);
DISPLAY 0.659574 (660 3560);
PAINT MONO (660 3560);
DISPLAY INVISIBLE (660 3560);
FORCEPROP 1 LASTPIN (650 3550) BN 1
J 2
(700 3560);
DISPLAY 0.617021 (700 3560);
PAINT PINK (700 3560);
FORCEPROP 2 LAST CDS_LIB mstr_standard
J 0
(700 3550);
DISPLAY 0.787234 (700 3550);
PAINT MONO (700 3550);
DISPLAY INVISIBLE (700 3550);
FORCEPROP 1 LAST BODY_TYPE PLUMBING
J 2
(700 3500);
DISPLAY 1.234043 (700 3500);
PAINT GREEN (700 3500);
DISPLAY INVISIBLE (700 3500);
FORCEPROP 1 LAST HDL_TAP TRUE
J 2
(375 3425);
DISPLAY 1.234043 (375 3425);
PAINT WHITE (375 3425);
DISPLAY INVISIBLE (375 3425);
FORCEPROP 1 LAST PATH I39
J 2
(700 3550);
DISPLAY 0.936170 (700 3550);
PAINT GREEN (700 3550);
DISPLAY INVISIBLE (700 3550);
FORCEADD TAP..6
R 2
(700 5150);
FORCEPROP 3 LASTPIN (650 5150) SIG_NAME M_C_DQS_DP<17>
J 0
(660 5160);
DISPLAY 0.659574 (660 5160);
PAINT MONO (660 5160);
DISPLAY INVISIBLE (660 5160);
FORCEPROP 1 LASTPIN (650 5150) BN 17
J 2
(700 5160);
DISPLAY 0.617021 (700 5160);
PAINT PINK (700 5160);
FORCEPROP 2 LAST CDS_LIB mstr_standard
J 2
(700 5150);
DISPLAY 0.787234 (700 5150);
PAINT MONO (700 5150);
DISPLAY INVISIBLE (700 5150);
FORCEPROP 1 LAST BODY_TYPE PLUMBING
J 2
(700 5100);
DISPLAY 1.234043 (700 5100);
PAINT GREEN (700 5100);
DISPLAY INVISIBLE (700 5100);
FORCEPROP 1 LAST HDL_TAP TRUE
J 2
(375 5025);
DISPLAY 1.234043 (375 5025);
PAINT WHITE (375 5025);
DISPLAY INVISIBLE (375 5025);
FORCEPROP 1 LAST PATH I4
J 2
(700 5150);
DISPLAY 0.936170 (700 5150);
PAINT GREEN (700 5150);
DISPLAY INVISIBLE (700 5150);
FORCEADD TAP..6
R 2
(900 3400);
FORCEPROP 3 LASTPIN (850 3400) SIG_NAME M_C_DQS_DN<0>
J 0
(860 3410);
DISPLAY 0.659574 (860 3410);
PAINT MONO (860 3410);
DISPLAY INVISIBLE (860 3410);
FORCEPROP 1 LASTPIN (850 3400) BN 0
J 2
(900 3410);
DISPLAY 0.617021 (900 3410);
PAINT PINK (900 3410);
FORCEPROP 2 LAST CDS_LIB mstr_standard
J 0
(900 3400);
DISPLAY 0.787234 (900 3400);
PAINT MONO (900 3400);
DISPLAY INVISIBLE (900 3400);
FORCEPROP 1 LAST BODY_TYPE PLUMBING
J 2
(900 3350);
DISPLAY 1.234043 (900 3350);
PAINT GREEN (900 3350);
DISPLAY INVISIBLE (900 3350);
FORCEPROP 1 LAST HDL_TAP TRUE
J 2
(575 3275);
DISPLAY 1.234043 (575 3275);
PAINT GREEN (575 3275);
DISPLAY INVISIBLE (575 3275);
FORCEPROP 1 LAST PATH I40
J 2
(900 3400);
DISPLAY 0.936170 (900 3400);
PAINT GREEN (900 3400);
DISPLAY INVISIBLE (900 3400);
FORCEADD TAP..6
R 2
(700 3450);
FORCEPROP 3 LASTPIN (650 3450) SIG_NAME M_C_DQS_DP<0>
J 0
(660 3460);
DISPLAY 0.659574 (660 3460);
PAINT MONO (660 3460);
DISPLAY INVISIBLE (660 3460);
FORCEPROP 1 LASTPIN (650 3450) BN 0
J 2
(700 3460);
DISPLAY 0.617021 (700 3460);
PAINT PINK (700 3460);
FORCEPROP 2 LAST CDS_LIB mstr_standard
J 0
(700 3450);
DISPLAY 0.787234 (700 3450);
PAINT MONO (700 3450);
DISPLAY INVISIBLE (700 3450);
FORCEPROP 1 LAST BODY_TYPE PLUMBING
J 2
(700 3400);
DISPLAY 1.234043 (700 3400);
PAINT GREEN (700 3400);
DISPLAY INVISIBLE (700 3400);
FORCEPROP 1 LAST HDL_TAP TRUE
J 2
(375 3325);
DISPLAY 1.234043 (375 3325);
PAINT WHITE (375 3325);
DISPLAY INVISIBLE (375 3325);
FORCEPROP 1 LAST PATH I41
J 2
(700 3450);
DISPLAY 0.936170 (700 3450);
PAINT GREEN (700 3450);
DISPLAY INVISIBLE (700 3450);
FORCEADD SCONN288_H44441003..3
(1800 2600);
FORCEPROP 1 LAST LOCATION J6U2
J 0
(1350 4000);
DISPLAY 0.617021 (1350 4000);
PAINT AQUA (1350 4000);
FORCEPROP 1 LAST PART_NUMBER H44441-003
J 0
(1350 1250);
DISPLAY 0.617021 (1350 1250);
PAINT BLUE (1350 1250);
FORCEPROP 1 LAST MATERIAL SCONN
J 0
(1350 3950);
DISPLAY 0.617021 (1350 3950);
PAINT SKYBLUE (1350 3950);
FORCEPROP 2 LASTPIN (1300 3750) $PN 2
J 2
(1290 3760);
DISPLAY 0.617021 (1290 3760);
PAINT ORANGE (1290 3760);
FORCEPROP 2 LASTPIN (1300 3700) $PN 4
J 2
(1290 3710);
DISPLAY 0.617021 (1290 3710);
PAINT ORANGE (1290 3710);
FORCEPROP 2 LASTPIN (1300 3650) $PN 6
J 2
(1290 3660);
DISPLAY 0.617021 (1290 3660);
PAINT ORANGE (1290 3660);
FORCEPROP 2 LASTPIN (1300 3600) $PN 9
J 2
(1290 3610);
DISPLAY 0.617021 (1290 3610);
PAINT ORANGE (1290 3610);
FORCEPROP 2 LASTPIN (1300 3550) $PN 11
J 2
(1290 3560);
DISPLAY 0.617021 (1290 3560);
PAINT ORANGE (1290 3560);
FORCEPROP 2 LASTPIN (1300 3500) $PN 13
J 2
(1290 3510);
DISPLAY 0.617021 (1290 3510);
PAINT ORANGE (1290 3510);
FORCEPROP 2 LASTPIN (1300 3450) $PN 15
J 2
(1290 3460);
DISPLAY 0.617021 (1290 3460);
PAINT ORANGE (1290 3460);
FORCEPROP 2 LASTPIN (1300 3400) $PN 17
J 2
(1290 3410);
DISPLAY 0.617021 (1290 3410);
PAINT ORANGE (1290 3410);
FORCEPROP 2 LASTPIN (1300 3350) $PN 20
J 2
(1290 3360);
DISPLAY 0.617021 (1290 3360);
PAINT ORANGE (1290 3360);
FORCEPROP 2 LASTPIN (1300 3300) $PN 22
J 2
(1290 3310);
DISPLAY 0.617021 (1290 3310);
PAINT ORANGE (1290 3310);
FORCEPROP 2 LASTPIN (1300 3250) $PN 24
J 2
(1290 3260);
DISPLAY 0.617021 (1290 3260);
PAINT ORANGE (1290 3260);
FORCEPROP 2 LASTPIN (1300 3200) $PN 26
J 2
(1290 3210);
DISPLAY 0.617021 (1290 3210);
PAINT ORANGE (1290 3210);
FORCEPROP 2 LASTPIN (1300 3150) $PN 28
J 2
(1290 3160);
DISPLAY 0.617021 (1290 3160);
PAINT ORANGE (1290 3160);
FORCEPROP 2 LASTPIN (1300 3100) $PN 31
J 2
(1290 3110);
DISPLAY 0.617021 (1290 3110);
PAINT ORANGE (1290 3110);
FORCEPROP 2 LASTPIN (1300 3050) $PN 33
J 2
(1290 3060);
DISPLAY 0.617021 (1290 3060);
PAINT ORANGE (1290 3060);
FORCEPROP 2 LASTPIN (1300 3000) $PN 35
J 2
(1290 3010);
DISPLAY 0.617021 (1290 3010);
PAINT ORANGE (1290 3010);
FORCEPROP 2 LASTPIN (1300 2950) $PN 37
J 2
(1290 2960);
DISPLAY 0.617021 (1290 2960);
PAINT ORANGE (1290 2960);
FORCEPROP 2 LASTPIN (1300 2900) $PN 39
J 2
(1290 2910);
DISPLAY 0.617021 (1290 2910);
PAINT ORANGE (1290 2910);
FORCEPROP 2 LASTPIN (1300 2850) $PN 42
J 2
(1290 2860);
DISPLAY 0.617021 (1290 2860);
PAINT ORANGE (1290 2860);
FORCEPROP 2 LASTPIN (1300 2800) $PN 44
J 2
(1290 2810);
DISPLAY 0.617021 (1290 2810);
PAINT ORANGE (1290 2810);
FORCEPROP 2 LASTPIN (1300 2750) $PN 46
J 2
(1290 2760);
DISPLAY 0.617021 (1290 2760);
PAINT ORANGE (1290 2760);
FORCEPROP 2 LASTPIN (1300 2700) $PN 48
J 2
(1290 2710);
DISPLAY 0.617021 (1290 2710);
PAINT ORANGE (1290 2710);
FORCEPROP 2 LASTPIN (1300 2650) $PN 50
J 2
(1290 2660);
DISPLAY 0.617021 (1290 2660);
PAINT ORANGE (1290 2660);
FORCEPROP 2 LASTPIN (1300 2600) $PN 53
J 2
(1290 2610);
DISPLAY 0.617021 (1290 2610);
PAINT ORANGE (1290 2610);
FORCEPROP 2 LASTPIN (1300 2550) $PN 55
J 2
(1290 2560);
DISPLAY 0.617021 (1290 2560);
PAINT ORANGE (1290 2560);
FORCEPROP 2 LASTPIN (1300 2500) $PN 57
J 2
(1290 2510);
DISPLAY 0.617021 (1290 2510);
PAINT ORANGE (1290 2510);
FORCEPROP 2 LASTPIN (1300 2450) $PN 94
J 2
(1290 2460);
DISPLAY 0.617021 (1290 2460);
PAINT ORANGE (1290 2460);
FORCEPROP 2 LASTPIN (1300 2400) $PN 96
J 2
(1290 2410);
DISPLAY 0.617021 (1290 2410);
PAINT ORANGE (1290 2410);
FORCEPROP 2 LASTPIN (1300 2350) $PN 98
J 2
(1290 2360);
DISPLAY 0.617021 (1290 2360);
PAINT ORANGE (1290 2360);
FORCEPROP 2 LASTPIN (1300 2300) $PN 101
J 2
(1290 2310);
DISPLAY 0.617021 (1290 2310);
PAINT ORANGE (1290 2310);
FORCEPROP 2 LASTPIN (1300 2250) $PN 103
J 2
(1290 2260);
DISPLAY 0.617021 (1290 2260);
PAINT ORANGE (1290 2260);
FORCEPROP 2 LASTPIN (1300 2200) $PN 105
J 2
(1290 2210);
DISPLAY 0.617021 (1290 2210);
PAINT ORANGE (1290 2210);
FORCEPROP 2 LASTPIN (1300 2150) $PN 107
J 2
(1290 2160);
DISPLAY 0.617021 (1290 2160);
PAINT ORANGE (1290 2160);
FORCEPROP 2 LASTPIN (1300 2100) $PN 109
J 2
(1290 2110);
DISPLAY 0.617021 (1290 2110);
PAINT ORANGE (1290 2110);
FORCEPROP 2 LASTPIN (1300 2050) $PN 112
J 2
(1290 2060);
DISPLAY 0.617021 (1290 2060);
PAINT ORANGE (1290 2060);
FORCEPROP 2 LASTPIN (1300 2000) $PN 114
J 2
(1290 2010);
DISPLAY 0.617021 (1290 2010);
PAINT ORANGE (1290 2010);
FORCEPROP 2 LASTPIN (1300 1950) $PN 116
J 2
(1290 1960);
DISPLAY 0.617021 (1290 1960);
PAINT ORANGE (1290 1960);
FORCEPROP 2 LASTPIN (1300 1900) $PN 118
J 2
(1290 1910);
DISPLAY 0.617021 (1290 1910);
PAINT ORANGE (1290 1910);
FORCEPROP 2 LASTPIN (1300 1850) $PN 120
J 2
(1290 1860);
DISPLAY 0.617021 (1290 1860);
PAINT ORANGE (1290 1860);
FORCEPROP 2 LASTPIN (1300 1800) $PN 123
J 2
(1290 1810);
DISPLAY 0.617021 (1290 1810);
PAINT ORANGE (1290 1810);
FORCEPROP 2 LASTPIN (1300 1750) $PN 125
J 2
(1290 1760);
DISPLAY 0.617021 (1290 1760);
PAINT ORANGE (1290 1760);
FORCEPROP 2 LASTPIN (1300 1700) $PN 127
J 2
(1290 1710);
DISPLAY 0.617021 (1290 1710);
PAINT ORANGE (1290 1710);
FORCEPROP 2 LASTPIN (1300 1650) $PN 129
J 2
(1290 1660);
DISPLAY 0.617021 (1290 1660);
PAINT ORANGE (1290 1660);
FORCEPROP 2 LASTPIN (1300 1600) $PN 131
J 2
(1290 1610);
DISPLAY 0.617021 (1290 1610);
PAINT ORANGE (1290 1610);
FORCEPROP 2 LASTPIN (1300 1550) $PN 134
J 2
(1290 1560);
DISPLAY 0.617021 (1290 1560);
PAINT ORANGE (1290 1560);
FORCEPROP 2 LASTPIN (1300 1500) $PN 136
J 2
(1290 1510);
DISPLAY 0.617021 (1290 1510);
PAINT ORANGE (1290 1510);
FORCEPROP 2 LASTPIN (1300 1450) $PN 138
J 2
(1290 1460);
DISPLAY 0.617021 (1290 1460);
PAINT ORANGE (1290 1460);
FORCEPROP 2 LASTPIN (2300 3750) $PN 147
J 0
(2310 3760);
DISPLAY 0.617021 (2310 3760);
PAINT ORANGE (2310 3760);
FORCEPROP 2 LASTPIN (2300 3700) $PN 149
J 0
(2310 3710);
DISPLAY 0.617021 (2310 3710);
PAINT ORANGE (2310 3710);
FORCEPROP 2 LASTPIN (2300 3650) $PN 151
J 0
(2310 3660);
DISPLAY 0.617021 (2310 3660);
PAINT ORANGE (2310 3660);
FORCEPROP 2 LASTPIN (2300 3600) $PN 154
J 0
(2310 3610);
DISPLAY 0.617021 (2310 3610);
PAINT ORANGE (2310 3610);
FORCEPROP 2 LASTPIN (2300 3550) $PN 156
J 0
(2310 3560);
DISPLAY 0.617021 (2310 3560);
PAINT ORANGE (2310 3560);
FORCEPROP 2 LASTPIN (2300 3500) $PN 158
J 0
(2310 3510);
DISPLAY 0.617021 (2310 3510);
PAINT ORANGE (2310 3510);
FORCEPROP 2 LASTPIN (2300 3450) $PN 160
J 0
(2310 3460);
DISPLAY 0.617021 (2310 3460);
PAINT ORANGE (2310 3460);
FORCEPROP 2 LASTPIN (2300 3400) $PN 162
J 0
(2310 3410);
DISPLAY 0.617021 (2310 3410);
PAINT ORANGE (2310 3410);
FORCEPROP 2 LASTPIN (2300 3350) $PN 165
J 0
(2310 3360);
DISPLAY 0.617021 (2310 3360);
PAINT ORANGE (2310 3360);
FORCEPROP 2 LASTPIN (2300 3300) $PN 167
J 0
(2310 3310);
DISPLAY 0.617021 (2310 3310);
PAINT ORANGE (2310 3310);
FORCEPROP 2 LASTPIN (2300 3250) $PN 169
J 0
(2310 3260);
DISPLAY 0.617021 (2310 3260);
PAINT ORANGE (2310 3260);
FORCEPROP 2 LASTPIN (2300 3200) $PN 171
J 0
(2310 3210);
DISPLAY 0.617021 (2310 3210);
PAINT ORANGE (2310 3210);
FORCEPROP 2 LASTPIN (2300 3150) $PN 173
J 0
(2310 3160);
DISPLAY 0.617021 (2310 3160);
PAINT ORANGE (2310 3160);
FORCEPROP 2 LASTPIN (2300 3100) $PN 176
J 0
(2310 3110);
DISPLAY 0.617021 (2310 3110);
PAINT ORANGE (2310 3110);
FORCEPROP 2 LASTPIN (2300 3050) $PN 178
J 0
(2310 3060);
DISPLAY 0.617021 (2310 3060);
PAINT ORANGE (2310 3060);
FORCEPROP 2 LASTPIN (2300 3000) $PN 180
J 0
(2310 3010);
DISPLAY 0.617021 (2310 3010);
PAINT ORANGE (2310 3010);
FORCEPROP 2 LASTPIN (2300 2950) $PN 182
J 0
(2310 2960);
DISPLAY 0.617021 (2310 2960);
PAINT ORANGE (2310 2960);
FORCEPROP 2 LASTPIN (2300 2900) $PN 184
J 0
(2310 2910);
DISPLAY 0.617021 (2310 2910);
PAINT ORANGE (2310 2910);
FORCEPROP 2 LASTPIN (2300 2850) $PN 187
J 0
(2310 2860);
DISPLAY 0.617021 (2310 2860);
PAINT ORANGE (2310 2860);
FORCEPROP 2 LASTPIN (2300 2800) $PN 189
J 0
(2310 2810);
DISPLAY 0.617021 (2310 2810);
PAINT ORANGE (2310 2810);
FORCEPROP 2 LASTPIN (2300 2750) $PN 191
J 0
(2310 2760);
DISPLAY 0.617021 (2310 2760);
PAINT ORANGE (2310 2760);
FORCEPROP 2 LASTPIN (2300 2700) $PN 193
J 0
(2310 2710);
DISPLAY 0.617021 (2310 2710);
PAINT ORANGE (2310 2710);
FORCEPROP 2 LASTPIN (2300 2650) $PN 195
J 0
(2310 2660);
DISPLAY 0.617021 (2310 2660);
PAINT ORANGE (2310 2660);
FORCEPROP 2 LASTPIN (2300 2600) $PN 198
J 0
(2310 2610);
DISPLAY 0.617021 (2310 2610);
PAINT ORANGE (2310 2610);
FORCEPROP 2 LASTPIN (2300 2550) $PN 200
J 0
(2310 2560);
DISPLAY 0.617021 (2310 2560);
PAINT ORANGE (2310 2560);
FORCEPROP 2 LASTPIN (2300 2500) $PN 202
J 0
(2310 2510);
DISPLAY 0.617021 (2310 2510);
PAINT ORANGE (2310 2510);
FORCEPROP 2 LASTPIN (2300 2450) $PN 239
J 0
(2310 2460);
DISPLAY 0.617021 (2310 2460);
PAINT ORANGE (2310 2460);
FORCEPROP 2 LASTPIN (2300 2400) $PN 241
J 0
(2310 2410);
DISPLAY 0.617021 (2310 2410);
PAINT ORANGE (2310 2410);
FORCEPROP 2 LASTPIN (2300 2350) $PN 243
J 0
(2310 2360);
DISPLAY 0.617021 (2310 2360);
PAINT ORANGE (2310 2360);
FORCEPROP 2 LASTPIN (2300 2300) $PN 246
J 0
(2310 2310);
DISPLAY 0.617021 (2310 2310);
PAINT ORANGE (2310 2310);
FORCEPROP 2 LASTPIN (2300 2250) $PN 248
J 0
(2310 2260);
DISPLAY 0.617021 (2310 2260);
PAINT ORANGE (2310 2260);
FORCEPROP 2 LASTPIN (2300 2200) $PN 250
J 0
(2310 2210);
DISPLAY 0.617021 (2310 2210);
PAINT ORANGE (2310 2210);
FORCEPROP 2 LASTPIN (2300 2150) $PN 252
J 0
(2310 2160);
DISPLAY 0.617021 (2310 2160);
PAINT ORANGE (2310 2160);
FORCEPROP 2 LASTPIN (2300 2100) $PN 254
J 0
(2310 2110);
DISPLAY 0.617021 (2310 2110);
PAINT ORANGE (2310 2110);
FORCEPROP 2 LASTPIN (2300 2050) $PN 257
J 0
(2310 2060);
DISPLAY 0.617021 (2310 2060);
PAINT ORANGE (2310 2060);
FORCEPROP 2 LASTPIN (2300 2000) $PN 259
J 0
(2310 2010);
DISPLAY 0.617021 (2310 2010);
PAINT ORANGE (2310 2010);
FORCEPROP 2 LASTPIN (2300 1950) $PN 261
J 0
(2310 1960);
DISPLAY 0.617021 (2310 1960);
PAINT ORANGE (2310 1960);
FORCEPROP 2 LASTPIN (2300 1900) $PN 263
J 0
(2310 1910);
DISPLAY 0.617021 (2310 1910);
PAINT ORANGE (2310 1910);
FORCEPROP 2 LASTPIN (2300 1850) $PN 265
J 0
(2310 1860);
DISPLAY 0.617021 (2310 1860);
PAINT ORANGE (2310 1860);
FORCEPROP 2 LASTPIN (2300 1800) $PN 268
J 0
(2310 1810);
DISPLAY 0.617021 (2310 1810);
PAINT ORANGE (2310 1810);
FORCEPROP 2 LASTPIN (2300 1750) $PN 270
J 0
(2310 1760);
DISPLAY 0.617021 (2310 1760);
PAINT ORANGE (2310 1760);
FORCEPROP 2 LASTPIN (2300 1700) $PN 272
J 0
(2310 1710);
DISPLAY 0.617021 (2310 1710);
PAINT ORANGE (2310 1710);
FORCEPROP 2 LASTPIN (2300 1650) $PN 274
J 0
(2310 1660);
DISPLAY 0.617021 (2310 1660);
PAINT ORANGE (2310 1660);
FORCEPROP 2 LASTPIN (2300 1600) $PN 276
J 0
(2310 1610);
DISPLAY 0.617021 (2310 1610);
PAINT ORANGE (2310 1610);
FORCEPROP 2 LASTPIN (2300 1550) $PN 279
J 0
(2310 1560);
DISPLAY 0.617021 (2310 1560);
PAINT ORANGE (2310 1560);
FORCEPROP 2 LASTPIN (2300 1500) $PN 281
J 0
(2310 1510);
DISPLAY 0.617021 (2310 1510);
PAINT ORANGE (2310 1510);
FORCEPROP 2 LASTPIN (2300 1450) $PN 283
J 0
(2310 1460);
DISPLAY 0.617021 (2310 1460);
PAINT ORANGE (2310 1460);
FORCEPROP 1 LAST PACK_TYPE PIP
J 0
(1350 4050);
PAINT SKYBLUE (1350 4050);
DISPLAY INVISIBLE (1350 4050);
FORCEPROP 2 LAST BOM_COST MEM
J 0
(1800 2600);
PAINT ORANGE (1800 2600);
DISPLAY INVISIBLE (1800 2600);
FORCEPROP 2 LAST CDS_LIB mstr_sconn
J 0
(1800 2600);
PAINT ORANGE (1800 2600);
DISPLAY INVISIBLE (1800 2600);
FORCEPROP 2 LAST SEC_TYPE PIP
J 0
(1350 4050);
DISPLAY 1.021277 (1350 4050);
PAINT ORANGE (1350 4050);
DISPLAY INVISIBLE (1350 4050);
FORCEPROP 2 LAST SEC 3
J 0
(1350 4050);
DISPLAY 0.680851 (1350 4050);
PAINT MONO (1350 4050);
DISPLAY INVISIBLE (1350 4050);
FORCEPROP 2 LAST CDS_LOCATION J6U2
J 0
(1350 4000);
DISPLAY 0.617021 (1350 4000);
PAINT AQUA (1350 4000);
DISPLAY INVISIBLE (1350 4000);
FORCEPROP 1 LAST PATH I43
J 0
(1800 3950);
PAINT GREEN (1800 3950);
DISPLAY INVISIBLE (1800 3950);
FORCEPROP 2 LAST ROOM DDR4_CH_C1
J 0
(1800 2600);
PAINT ORANGE (1800 2600);
DISPLAY INVISIBLE (1800 2600);
FORCEADD GND..1
R 2
(1100 1300);
FORCEPROP 3 LASTPIN (1100 1350) SIG_NAME GND\g
J 0
(1110 1360);
DISPLAY 0.659574 (1110 1360);
PAINT MONO (1110 1360);
DISPLAY INVISIBLE (1110 1360);
FORCEPROP 1 LAST VOLTAGE 0
J 0
(1100 1300);
PAINT SKYBLUE (1100 1300);
DISPLAY INVISIBLE (1100 1300);
FORCEPROP 2 LAST CDS_LIB mstr_symbols
J 0
(1100 1300);
DISPLAY 0.787234 (1100 1300);
PAINT MONO (1100 1300);
DISPLAY INVISIBLE (1100 1300);
FORCEPROP 1 LAST SIZE 1B
J 2
(1025 1250);
DISPLAY 1.170213 (1025 1250);
PAINT GREEN (1025 1250);
DISPLAY INVISIBLE (1025 1250);
FORCEPROP 2 LAST BOM_COST MEM
J 0
(1100 1305);
PAINT ORANGE (1100 1305);
DISPLAY INVISIBLE (1100 1305);
FORCEPROP 1 LAST BODY_TYPE PLUMBING
J 2
(1145 1257);
DISPLAY 0.340426 (1145 1257);
PAINT GREEN (1145 1257);
DISPLAY INVISIBLE (1145 1257);
FORCEPROP 1 LAST PATH I44
J 2
(1025 1300);
DISPLAY 0.936170 (1025 1300);
PAINT GREEN (1025 1300);
DISPLAY INVISIBLE (1025 1300);
FORCEPROP 2 LAST ROOM DDR4_CH_B
J 0
(1100 1305);
PAINT ORANGE (1100 1305);
DISPLAY INVISIBLE (1100 1305);
FORCEPROP 1 LAST HDL_POWER GND
J 2
(1100 1450);
DISPLAY 0.553191 (1100 1450);
PAINT GREEN (1100 1450);
DISPLAY INVISIBLE (1100 1450);
FORCEADD OFFPAGE..3
(-1100 4900);
FORCEPROP 2 LAST $XR0 25 
J 0
(-886 4900);
DISPLAY 0.638298 (-886 4900);
PAINT MONO (-886 4900);
FORCEPROP 2 LAST $XR1 47 
J 0
(-796 4900);
DISPLAY 0.638298 (-796 4900);
PAINT MONO (-796 4900);
FORCEPROP 2 LAST CDS_LIB mstr_standard
J 0
(-1100 4900);
DISPLAY 0.787234 (-1100 4900);
PAINT MONO (-1100 4900);
DISPLAY INVISIBLE (-1100 4900);
FORCEPROP 1 LAST OFFPAGE TRUE
J 0
(-775 4775);
DISPLAY 0.936170 (-775 4775);
PAINT GREEN (-775 4775);
DISPLAY INVISIBLE (-775 4775);
FORCEPROP 1 LAST COMMENT_BODY TRUE
J 0
(-1150 4800);
DISPLAY 0.936170 (-1150 4800);
PAINT GREEN (-1150 4800);
DISPLAY INVISIBLE (-1150 4800);
FORCEPROP 2 LAST PATH I45
J 0
(-900 4975);
DISPLAY 0.787234 (-900 4975);
PAINT MONO (-900 4975);
DISPLAY INVISIBLE (-900 4975);
FORCEADD TAP..6
R 2
(-1650 4850);
FORCEPROP 3 LASTPIN (-1700 4850) SIG_NAME M_C_DQ<63>
J 0
(-1690 4860);
DISPLAY 0.659574 (-1690 4860);
PAINT MONO (-1690 4860);
DISPLAY INVISIBLE (-1690 4860);
FORCEPROP 1 LASTPIN (-1700 4850) BN 63
J 2
(-1650 4860);
DISPLAY 0.617021 (-1650 4860);
PAINT PINK (-1650 4860);
FORCEPROP 2 LAST CDS_LIB mstr_standard
J 2
(-1650 4850);
DISPLAY 0.787234 (-1650 4850);
PAINT MONO (-1650 4850);
DISPLAY INVISIBLE (-1650 4850);
FORCEPROP 1 LAST BODY_TYPE PLUMBING
J 2
(-1650 4800);
DISPLAY 1.234043 (-1650 4800);
PAINT GREEN (-1650 4800);
DISPLAY INVISIBLE (-1650 4800);
FORCEPROP 1 LAST HDL_TAP TRUE
J 2
(-1975 4725);
DISPLAY 1.234043 (-1975 4725);
PAINT GREEN (-1975 4725);
DISPLAY INVISIBLE (-1975 4725);
FORCEPROP 1 LAST PATH I46
J 2
(-1650 4850);
DISPLAY 0.936170 (-1650 4850);
PAINT GREEN (-1650 4850);
DISPLAY INVISIBLE (-1650 4850);
FORCEADD TAP..6
R 2
(-1650 4800);
FORCEPROP 3 LASTPIN (-1700 4800) SIG_NAME M_C_DQ<62>
J 0
(-1690 4810);
DISPLAY 0.659574 (-1690 4810);
PAINT MONO (-1690 4810);
DISPLAY INVISIBLE (-1690 4810);
FORCEPROP 1 LASTPIN (-1700 4800) BN 62
J 2
(-1650 4810);
DISPLAY 0.617021 (-1650 4810);
PAINT PINK (-1650 4810);
FORCEPROP 2 LAST CDS_LIB mstr_standard
J 2
(-1650 4800);
DISPLAY 0.787234 (-1650 4800);
PAINT MONO (-1650 4800);
DISPLAY INVISIBLE (-1650 4800);
FORCEPROP 1 LAST BODY_TYPE PLUMBING
J 2
(-1650 4750);
DISPLAY 1.234043 (-1650 4750);
PAINT GREEN (-1650 4750);
DISPLAY INVISIBLE (-1650 4750);
FORCEPROP 1 LAST HDL_TAP TRUE
J 2
(-1975 4675);
DISPLAY 1.234043 (-1975 4675);
PAINT GREEN (-1975 4675);
DISPLAY INVISIBLE (-1975 4675);
FORCEPROP 1 LAST PATH I47
J 2
(-1650 4800);
DISPLAY 0.936170 (-1650 4800);
PAINT GREEN (-1650 4800);
DISPLAY INVISIBLE (-1650 4800);
FORCEADD TAP..6
R 2
(-1650 4650);
FORCEPROP 3 LASTPIN (-1700 4650) SIG_NAME M_C_DQ<59>
J 0
(-1690 4660);
DISPLAY 0.659574 (-1690 4660);
PAINT MONO (-1690 4660);
DISPLAY INVISIBLE (-1690 4660);
FORCEPROP 1 LASTPIN (-1700 4650) BN 59
J 2
(-1650 4660);
DISPLAY 0.617021 (-1650 4660);
PAINT PINK (-1650 4660);
FORCEPROP 2 LAST CDS_LIB mstr_standard
J 2
(-1650 4650);
DISPLAY 0.787234 (-1650 4650);
PAINT MONO (-1650 4650);
DISPLAY INVISIBLE (-1650 4650);
FORCEPROP 1 LAST BODY_TYPE PLUMBING
J 2
(-1650 4600);
DISPLAY 1.234043 (-1650 4600);
PAINT GREEN (-1650 4600);
DISPLAY INVISIBLE (-1650 4600);
FORCEPROP 1 LAST HDL_TAP TRUE
J 2
(-1975 4525);
DISPLAY 1.234043 (-1975 4525);
PAINT GREEN (-1975 4525);
DISPLAY INVISIBLE (-1975 4525);
FORCEPROP 1 LAST PATH I48
J 2
(-1650 4650);
DISPLAY 0.936170 (-1650 4650);
PAINT GREEN (-1650 4650);
DISPLAY INVISIBLE (-1650 4650);
FORCEADD TAP..6
R 2
(-1650 4700);
FORCEPROP 3 LASTPIN (-1700 4700) SIG_NAME M_C_DQ<60>
J 0
(-1690 4710);
DISPLAY 0.659574 (-1690 4710);
PAINT MONO (-1690 4710);
DISPLAY INVISIBLE (-1690 4710);
FORCEPROP 1 LASTPIN (-1700 4700) BN 60
J 2
(-1650 4710);
DISPLAY 0.617021 (-1650 4710);
PAINT PINK (-1650 4710);
FORCEPROP 2 LAST CDS_LIB mstr_standard
J 2
(-1650 4700);
DISPLAY 0.787234 (-1650 4700);
PAINT MONO (-1650 4700);
DISPLAY INVISIBLE (-1650 4700);
FORCEPROP 1 LAST BODY_TYPE PLUMBING
J 2
(-1650 4650);
DISPLAY 1.234043 (-1650 4650);
PAINT GREEN (-1650 4650);
DISPLAY INVISIBLE (-1650 4650);
FORCEPROP 1 LAST HDL_TAP TRUE
J 2
(-1975 4575);
DISPLAY 1.234043 (-1975 4575);
PAINT GREEN (-1975 4575);
DISPLAY INVISIBLE (-1975 4575);
FORCEPROP 1 LAST PATH I49
J 2
(-1650 4700);
DISPLAY 0.936170 (-1650 4700);
PAINT GREEN (-1650 4700);
DISPLAY INVISIBLE (-1650 4700);
FORCEADD TAP..6
R 2
(700 5050);
FORCEPROP 3 LASTPIN (650 5050) SIG_NAME M_C_DQS_DP<16>
J 0
(660 5060);
DISPLAY 0.659574 (660 5060);
PAINT MONO (660 5060);
DISPLAY INVISIBLE (660 5060);
FORCEPROP 1 LASTPIN (650 5050) BN 16
J 2
(700 5060);
DISPLAY 0.617021 (700 5060);
PAINT PINK (700 5060);
FORCEPROP 2 LAST CDS_LIB mstr_standard
J 0
(700 5050);
DISPLAY 0.787234 (700 5050);
PAINT MONO (700 5050);
DISPLAY INVISIBLE (700 5050);
FORCEPROP 1 LAST BODY_TYPE PLUMBING
J 2
(700 5000);
DISPLAY 1.234043 (700 5000);
PAINT GREEN (700 5000);
DISPLAY INVISIBLE (700 5000);
FORCEPROP 1 LAST HDL_TAP TRUE
J 2
(375 4925);
DISPLAY 1.234043 (375 4925);
PAINT WHITE (375 4925);
DISPLAY INVISIBLE (375 4925);
FORCEPROP 1 LAST PATH I5
J 2
(700 5050);
DISPLAY 0.936170 (700 5050);
PAINT GREEN (700 5050);
DISPLAY INVISIBLE (700 5050);
FORCEADD TAP..6
R 2
(-1650 4750);
FORCEPROP 3 LASTPIN (-1700 4750) SIG_NAME M_C_DQ<61>
J 0
(-1690 4760);
DISPLAY 0.659574 (-1690 4760);
PAINT MONO (-1690 4760);
DISPLAY INVISIBLE (-1690 4760);
FORCEPROP 1 LASTPIN (-1700 4750) BN 61
J 2
(-1650 4760);
DISPLAY 0.617021 (-1650 4760);
PAINT PINK (-1650 4760);
FORCEPROP 2 LAST CDS_LIB mstr_standard
J 2
(-1650 4750);
DISPLAY 0.787234 (-1650 4750);
PAINT MONO (-1650 4750);
DISPLAY INVISIBLE (-1650 4750);
FORCEPROP 1 LAST BODY_TYPE PLUMBING
J 2
(-1650 4700);
DISPLAY 1.234043 (-1650 4700);
PAINT GREEN (-1650 4700);
DISPLAY INVISIBLE (-1650 4700);
FORCEPROP 1 LAST HDL_TAP TRUE
J 2
(-1975 4625);
DISPLAY 1.234043 (-1975 4625);
PAINT GREEN (-1975 4625);
DISPLAY INVISIBLE (-1975 4625);
FORCEPROP 1 LAST PATH I50
J 2
(-1650 4750);
DISPLAY 0.936170 (-1650 4750);
PAINT GREEN (-1650 4750);
DISPLAY INVISIBLE (-1650 4750);
FORCEADD TAP..6
R 2
(-1650 4550);
FORCEPROP 3 LASTPIN (-1700 4550) SIG_NAME M_C_DQ<57>
J 0
(-1690 4560);
DISPLAY 0.659574 (-1690 4560);
PAINT MONO (-1690 4560);
DISPLAY INVISIBLE (-1690 4560);
FORCEPROP 1 LASTPIN (-1700 4550) BN 57
J 2
(-1650 4560);
DISPLAY 0.617021 (-1650 4560);
PAINT PINK (-1650 4560);
FORCEPROP 2 LAST CDS_LIB mstr_standard
J 2
(-1650 4550);
DISPLAY 0.787234 (-1650 4550);
PAINT MONO (-1650 4550);
DISPLAY INVISIBLE (-1650 4550);
FORCEPROP 1 LAST BODY_TYPE PLUMBING
J 2
(-1650 4500);
DISPLAY 1.234043 (-1650 4500);
PAINT GREEN (-1650 4500);
DISPLAY INVISIBLE (-1650 4500);
FORCEPROP 1 LAST HDL_TAP TRUE
J 2
(-1975 4425);
DISPLAY 1.234043 (-1975 4425);
PAINT GREEN (-1975 4425);
DISPLAY INVISIBLE (-1975 4425);
FORCEPROP 1 LAST PATH I51
J 2
(-1650 4550);
DISPLAY 0.936170 (-1650 4550);
PAINT GREEN (-1650 4550);
DISPLAY INVISIBLE (-1650 4550);
FORCEADD TAP..6
R 2
(-1650 4600);
FORCEPROP 3 LASTPIN (-1700 4600) SIG_NAME M_C_DQ<58>
J 0
(-1690 4610);
DISPLAY 0.659574 (-1690 4610);
PAINT MONO (-1690 4610);
DISPLAY INVISIBLE (-1690 4610);
FORCEPROP 1 LASTPIN (-1700 4600) BN 58
J 2
(-1650 4610);
DISPLAY 0.617021 (-1650 4610);
PAINT PINK (-1650 4610);
FORCEPROP 2 LAST CDS_LIB mstr_standard
J 2
(-1650 4600);
DISPLAY 0.787234 (-1650 4600);
PAINT MONO (-1650 4600);
DISPLAY INVISIBLE (-1650 4600);
FORCEPROP 1 LAST BODY_TYPE PLUMBING
J 2
(-1650 4550);
DISPLAY 1.234043 (-1650 4550);
PAINT GREEN (-1650 4550);
DISPLAY INVISIBLE (-1650 4550);
FORCEPROP 1 LAST HDL_TAP TRUE
J 2
(-1975 4475);
DISPLAY 1.234043 (-1975 4475);
PAINT GREEN (-1975 4475);
DISPLAY INVISIBLE (-1975 4475);
FORCEPROP 1 LAST PATH I52
J 2
(-1650 4600);
DISPLAY 0.936170 (-1650 4600);
PAINT GREEN (-1650 4600);
DISPLAY INVISIBLE (-1650 4600);
FORCEADD TAP..6
R 2
(-1650 4400);
FORCEPROP 3 LASTPIN (-1700 4400) SIG_NAME M_C_DQ<54>
J 0
(-1690 4410);
DISPLAY 0.659574 (-1690 4410);
PAINT MONO (-1690 4410);
DISPLAY INVISIBLE (-1690 4410);
FORCEPROP 1 LASTPIN (-1700 4400) BN 54
J 2
(-1650 4410);
DISPLAY 0.617021 (-1650 4410);
PAINT PINK (-1650 4410);
FORCEPROP 2 LAST CDS_LIB mstr_standard
J 2
(-1650 4400);
DISPLAY 0.787234 (-1650 4400);
PAINT MONO (-1650 4400);
DISPLAY INVISIBLE (-1650 4400);
FORCEPROP 1 LAST BODY_TYPE PLUMBING
J 2
(-1650 4350);
DISPLAY 1.234043 (-1650 4350);
PAINT GREEN (-1650 4350);
DISPLAY INVISIBLE (-1650 4350);
FORCEPROP 1 LAST HDL_TAP TRUE
J 2
(-1975 4275);
DISPLAY 1.234043 (-1975 4275);
PAINT GREEN (-1975 4275);
DISPLAY INVISIBLE (-1975 4275);
FORCEPROP 1 LAST PATH I53
J 2
(-1650 4400);
DISPLAY 0.936170 (-1650 4400);
PAINT GREEN (-1650 4400);
DISPLAY INVISIBLE (-1650 4400);
FORCEADD TAP..6
R 2
(-1650 4450);
FORCEPROP 3 LASTPIN (-1700 4450) SIG_NAME M_C_DQ<55>
J 0
(-1690 4460);
DISPLAY 0.659574 (-1690 4460);
PAINT MONO (-1690 4460);
DISPLAY INVISIBLE (-1690 4460);
FORCEPROP 1 LASTPIN (-1700 4450) BN 55
J 2
(-1650 4460);
DISPLAY 0.617021 (-1650 4460);
PAINT PINK (-1650 4460);
FORCEPROP 2 LAST CDS_LIB mstr_standard
J 2
(-1650 4450);
DISPLAY 0.787234 (-1650 4450);
PAINT MONO (-1650 4450);
DISPLAY INVISIBLE (-1650 4450);
FORCEPROP 1 LAST BODY_TYPE PLUMBING
J 2
(-1650 4400);
DISPLAY 1.234043 (-1650 4400);
PAINT GREEN (-1650 4400);
DISPLAY INVISIBLE (-1650 4400);
FORCEPROP 1 LAST HDL_TAP TRUE
J 2
(-1975 4325);
DISPLAY 1.234043 (-1975 4325);
PAINT GREEN (-1975 4325);
DISPLAY INVISIBLE (-1975 4325);
FORCEPROP 1 LAST PATH I54
J 2
(-1650 4450);
DISPLAY 0.936170 (-1650 4450);
PAINT GREEN (-1650 4450);
DISPLAY INVISIBLE (-1650 4450);
FORCEADD TAP..6
R 2
(-1650 4500);
FORCEPROP 3 LASTPIN (-1700 4500) SIG_NAME M_C_DQ<56>
J 0
(-1690 4510);
DISPLAY 0.659574 (-1690 4510);
PAINT MONO (-1690 4510);
DISPLAY INVISIBLE (-1690 4510);
FORCEPROP 1 LASTPIN (-1700 4500) BN 56
J 2
(-1650 4510);
DISPLAY 0.617021 (-1650 4510);
PAINT PINK (-1650 4510);
FORCEPROP 2 LAST CDS_LIB mstr_standard
J 2
(-1650 4500);
DISPLAY 0.787234 (-1650 4500);
PAINT MONO (-1650 4500);
DISPLAY INVISIBLE (-1650 4500);
FORCEPROP 1 LAST BODY_TYPE PLUMBING
J 2
(-1650 4450);
DISPLAY 1.234043 (-1650 4450);
PAINT GREEN (-1650 4450);
DISPLAY INVISIBLE (-1650 4450);
FORCEPROP 1 LAST HDL_TAP TRUE
J 2
(-1975 4375);
DISPLAY 1.234043 (-1975 4375);
PAINT GREEN (-1975 4375);
DISPLAY INVISIBLE (-1975 4375);
FORCEPROP 1 LAST PATH I55
J 2
(-1650 4500);
DISPLAY 0.936170 (-1650 4500);
PAINT GREEN (-1650 4500);
DISPLAY INVISIBLE (-1650 4500);
FORCEADD TAP..6
R 2
(-1650 4300);
FORCEPROP 3 LASTPIN (-1700 4300) SIG_NAME M_C_DQ<52>
J 0
(-1690 4310);
DISPLAY 0.659574 (-1690 4310);
PAINT MONO (-1690 4310);
DISPLAY INVISIBLE (-1690 4310);
FORCEPROP 1 LASTPIN (-1700 4300) BN 52
J 2
(-1650 4310);
DISPLAY 0.617021 (-1650 4310);
PAINT PINK (-1650 4310);
FORCEPROP 2 LAST CDS_LIB mstr_standard
J 2
(-1650 4300);
DISPLAY 0.787234 (-1650 4300);
PAINT MONO (-1650 4300);
DISPLAY INVISIBLE (-1650 4300);
FORCEPROP 1 LAST BODY_TYPE PLUMBING
J 2
(-1650 4250);
DISPLAY 1.234043 (-1650 4250);
PAINT GREEN (-1650 4250);
DISPLAY INVISIBLE (-1650 4250);
FORCEPROP 1 LAST HDL_TAP TRUE
J 2
(-1975 4175);
DISPLAY 1.234043 (-1975 4175);
PAINT GREEN (-1975 4175);
DISPLAY INVISIBLE (-1975 4175);
FORCEPROP 1 LAST PATH I56
J 2
(-1650 4300);
DISPLAY 0.936170 (-1650 4300);
PAINT GREEN (-1650 4300);
DISPLAY INVISIBLE (-1650 4300);
FORCEADD TAP..6
R 2
(-1650 4350);
FORCEPROP 3 LASTPIN (-1700 4350) SIG_NAME M_C_DQ<53>
J 0
(-1690 4360);
DISPLAY 0.659574 (-1690 4360);
PAINT MONO (-1690 4360);
DISPLAY INVISIBLE (-1690 4360);
FORCEPROP 1 LASTPIN (-1700 4350) BN 53
J 2
(-1650 4360);
DISPLAY 0.617021 (-1650 4360);
PAINT PINK (-1650 4360);
FORCEPROP 2 LAST CDS_LIB mstr_standard
J 2
(-1650 4350);
DISPLAY 0.787234 (-1650 4350);
PAINT MONO (-1650 4350);
DISPLAY INVISIBLE (-1650 4350);
FORCEPROP 1 LAST BODY_TYPE PLUMBING
J 2
(-1650 4300);
DISPLAY 1.234043 (-1650 4300);
PAINT GREEN (-1650 4300);
DISPLAY INVISIBLE (-1650 4300);
FORCEPROP 1 LAST HDL_TAP TRUE
J 2
(-1975 4225);
DISPLAY 1.234043 (-1975 4225);
PAINT GREEN (-1975 4225);
DISPLAY INVISIBLE (-1975 4225);
FORCEPROP 1 LAST PATH I57
J 2
(-1650 4350);
DISPLAY 0.936170 (-1650 4350);
PAINT GREEN (-1650 4350);
DISPLAY INVISIBLE (-1650 4350);
FORCEADD TAP..6
R 2
(-1650 4250);
FORCEPROP 3 LASTPIN (-1700 4250) SIG_NAME M_C_DQ<51>
J 0
(-1690 4260);
DISPLAY 0.659574 (-1690 4260);
PAINT MONO (-1690 4260);
DISPLAY INVISIBLE (-1690 4260);
FORCEPROP 1 LASTPIN (-1700 4250) BN 51
J 2
(-1650 4260);
DISPLAY 0.617021 (-1650 4260);
PAINT PINK (-1650 4260);
FORCEPROP 2 LAST CDS_LIB mstr_standard
J 2
(-1650 4250);
DISPLAY 0.787234 (-1650 4250);
PAINT MONO (-1650 4250);
DISPLAY INVISIBLE (-1650 4250);
FORCEPROP 1 LAST BODY_TYPE PLUMBING
J 2
(-1650 4200);
DISPLAY 1.234043 (-1650 4200);
PAINT GREEN (-1650 4200);
DISPLAY INVISIBLE (-1650 4200);
FORCEPROP 1 LAST HDL_TAP TRUE
J 2
(-1975 4125);
DISPLAY 1.234043 (-1975 4125);
PAINT GREEN (-1975 4125);
DISPLAY INVISIBLE (-1975 4125);
FORCEPROP 1 LAST PATH I58
J 2
(-1650 4250);
DISPLAY 0.936170 (-1650 4250);
PAINT GREEN (-1650 4250);
DISPLAY INVISIBLE (-1650 4250);
FORCEADD TAP..6
R 2
(-1650 4200);
FORCEPROP 3 LASTPIN (-1700 4200) SIG_NAME M_C_DQ<50>
J 0
(-1690 4210);
DISPLAY 0.659574 (-1690 4210);
PAINT MONO (-1690 4210);
DISPLAY INVISIBLE (-1690 4210);
FORCEPROP 1 LASTPIN (-1700 4200) BN 50
J 2
(-1650 4210);
DISPLAY 0.617021 (-1650 4210);
PAINT PINK (-1650 4210);
FORCEPROP 2 LAST CDS_LIB mstr_standard
J 2
(-1650 4200);
DISPLAY 0.787234 (-1650 4200);
PAINT MONO (-1650 4200);
DISPLAY INVISIBLE (-1650 4200);
FORCEPROP 1 LAST BODY_TYPE PLUMBING
J 2
(-1650 4150);
DISPLAY 1.234043 (-1650 4150);
PAINT GREEN (-1650 4150);
DISPLAY INVISIBLE (-1650 4150);
FORCEPROP 1 LAST HDL_TAP TRUE
J 2
(-1975 4075);
DISPLAY 1.234043 (-1975 4075);
PAINT GREEN (-1975 4075);
DISPLAY INVISIBLE (-1975 4075);
FORCEPROP 1 LAST PATH I59
J 2
(-1650 4200);
DISPLAY 0.936170 (-1650 4200);
PAINT GREEN (-1650 4200);
DISPLAY INVISIBLE (-1650 4200);
FORCEADD TAP..6
R 2
(900 4900);
FORCEPROP 3 LASTPIN (850 4900) SIG_NAME M_C_DQS_DN<15>
J 0
(860 4910);
DISPLAY 0.659574 (860 4910);
PAINT MONO (860 4910);
DISPLAY INVISIBLE (860 4910);
FORCEPROP 1 LASTPIN (850 4900) BN 15
J 2
(900 4910);
DISPLAY 0.617021 (900 4910);
PAINT PINK (900 4910);
FORCEPROP 2 LAST CDS_LIB mstr_standard
J 0
(900 4900);
DISPLAY 0.787234 (900 4900);
PAINT MONO (900 4900);
DISPLAY INVISIBLE (900 4900);
FORCEPROP 1 LAST BODY_TYPE PLUMBING
J 2
(900 4850);
DISPLAY 1.234043 (900 4850);
PAINT GREEN (900 4850);
DISPLAY INVISIBLE (900 4850);
FORCEPROP 1 LAST HDL_TAP TRUE
J 2
(575 4775);
DISPLAY 1.234043 (575 4775);
PAINT GREEN (575 4775);
DISPLAY INVISIBLE (575 4775);
FORCEPROP 1 LAST PATH I6
J 2
(900 4900);
DISPLAY 0.936170 (900 4900);
PAINT GREEN (900 4900);
DISPLAY INVISIBLE (900 4900);
FORCEADD TAP..6
R 2
(-1650 4150);
FORCEPROP 3 LASTPIN (-1700 4150) SIG_NAME M_C_DQ<49>
J 0
(-1690 4160);
DISPLAY 0.659574 (-1690 4160);
PAINT MONO (-1690 4160);
DISPLAY INVISIBLE (-1690 4160);
FORCEPROP 1 LASTPIN (-1700 4150) BN 49
J 2
(-1650 4160);
DISPLAY 0.617021 (-1650 4160);
PAINT PINK (-1650 4160);
FORCEPROP 2 LAST CDS_LIB mstr_standard
J 2
(-1650 4150);
DISPLAY 0.787234 (-1650 4150);
PAINT MONO (-1650 4150);
DISPLAY INVISIBLE (-1650 4150);
FORCEPROP 1 LAST BODY_TYPE PLUMBING
J 2
(-1650 4100);
DISPLAY 1.234043 (-1650 4100);
PAINT GREEN (-1650 4100);
DISPLAY INVISIBLE (-1650 4100);
FORCEPROP 1 LAST HDL_TAP TRUE
J 2
(-1975 4025);
DISPLAY 1.234043 (-1975 4025);
PAINT GREEN (-1975 4025);
DISPLAY INVISIBLE (-1975 4025);
FORCEPROP 1 LAST PATH I60
J 2
(-1650 4150);
DISPLAY 0.936170 (-1650 4150);
PAINT GREEN (-1650 4150);
DISPLAY INVISIBLE (-1650 4150);
FORCEADD SCONN288_H44441003..2
(0 4300);
FORCEPROP 1 LAST LOCATION J6U2
J 0
(-400 5400);
DISPLAY 0.617021 (-400 5400);
PAINT AQUA (-400 5400);
FORCEPROP 1 LAST PART_NUMBER H44441-003
J 0
(-400 3200);
DISPLAY 0.617021 (-400 3200);
PAINT BLUE (-400 3200);
FORCEPROP 1 LAST MATERIAL SCONN
J 0
(-400 5350);
DISPLAY 0.617021 (-400 5350);
PAINT SKYBLUE (-400 5350);
FORCEPROP 2 LASTPIN (450 5150) $PN 51
J 0
(460 5160);
DISPLAY 0.617021 (460 5160);
PAINT ORANGE (460 5160);
FORCEPROP 2 LASTPIN (450 5100) $PN 52
J 0
(460 5110);
DISPLAY 0.617021 (460 5110);
PAINT ORANGE (460 5110);
FORCEPROP 2 LASTPIN (450 5050) $PN 132
J 0
(460 5060);
DISPLAY 0.617021 (460 5060);
PAINT ORANGE (460 5060);
FORCEPROP 2 LASTPIN (450 5000) $PN 133
J 0
(460 5010);
DISPLAY 0.617021 (460 5010);
PAINT ORANGE (460 5010);
FORCEPROP 2 LASTPIN (450 4950) $PN 121
J 0
(460 4960);
DISPLAY 0.617021 (460 4960);
PAINT ORANGE (460 4960);
FORCEPROP 2 LASTPIN (450 4900) $PN 122
J 0
(460 4910);
DISPLAY 0.617021 (460 4910);
PAINT ORANGE (460 4910);
FORCEPROP 2 LASTPIN (450 4850) $PN 110
J 0
(460 4860);
DISPLAY 0.617021 (460 4860);
PAINT ORANGE (460 4860);
FORCEPROP 2 LASTPIN (450 4800) $PN 111
J 0
(460 4810);
DISPLAY 0.617021 (460 4810);
PAINT ORANGE (460 4810);
FORCEPROP 2 LASTPIN (450 4750) $PN 99
J 0
(460 4760);
DISPLAY 0.617021 (460 4760);
PAINT ORANGE (460 4760);
FORCEPROP 2 LASTPIN (450 4700) $PN 100
J 0
(460 4710);
DISPLAY 0.617021 (460 4710);
PAINT ORANGE (460 4710);
FORCEPROP 2 LASTPIN (450 4650) $PN 40
J 0
(460 4660);
DISPLAY 0.617021 (460 4660);
PAINT ORANGE (460 4660);
FORCEPROP 2 LASTPIN (450 4600) $PN 41
J 0
(460 4610);
DISPLAY 0.617021 (460 4610);
PAINT ORANGE (460 4610);
FORCEPROP 2 LASTPIN (450 4550) $PN 29
J 0
(460 4560);
DISPLAY 0.617021 (460 4560);
PAINT ORANGE (460 4560);
FORCEPROP 2 LASTPIN (450 4500) $PN 30
J 0
(460 4510);
DISPLAY 0.617021 (460 4510);
PAINT ORANGE (460 4510);
FORCEPROP 2 LASTPIN (450 4450) $PN 18
J 0
(460 4460);
DISPLAY 0.617021 (460 4460);
PAINT ORANGE (460 4460);
FORCEPROP 2 LASTPIN (450 4400) $PN 19
J 0
(460 4410);
DISPLAY 0.617021 (460 4410);
PAINT ORANGE (460 4410);
FORCEPROP 2 LASTPIN (450 4350) $PN 7
J 0
(460 4360);
DISPLAY 0.617021 (460 4360);
PAINT ORANGE (460 4360);
FORCEPROP 2 LASTPIN (450 4300) $PN 8
J 0
(460 4310);
DISPLAY 0.617021 (460 4310);
PAINT ORANGE (460 4310);
FORCEPROP 2 LASTPIN (450 4250) $PN 197
J 0
(460 4260);
DISPLAY 0.617021 (460 4260);
PAINT ORANGE (460 4260);
FORCEPROP 2 LASTPIN (450 4200) $PN 196
J 0
(460 4210);
DISPLAY 0.617021 (460 4210);
PAINT ORANGE (460 4210);
FORCEPROP 2 LASTPIN (450 4150) $PN 278
J 0
(460 4160);
DISPLAY 0.617021 (460 4160);
PAINT ORANGE (460 4160);
FORCEPROP 2 LASTPIN (450 4100) $PN 277
J 0
(460 4110);
DISPLAY 0.617021 (460 4110);
PAINT ORANGE (460 4110);
FORCEPROP 2 LASTPIN (450 4050) $PN 267
J 0
(460 4060);
DISPLAY 0.617021 (460 4060);
PAINT ORANGE (460 4060);
FORCEPROP 2 LASTPIN (450 4000) $PN 266
J 0
(460 4010);
DISPLAY 0.617021 (460 4010);
PAINT ORANGE (460 4010);
FORCEPROP 2 LASTPIN (450 3950) $PN 256
J 0
(460 3960);
DISPLAY 0.617021 (460 3960);
PAINT ORANGE (460 3960);
FORCEPROP 2 LASTPIN (450 3900) $PN 255
J 0
(460 3910);
DISPLAY 0.617021 (460 3910);
PAINT ORANGE (460 3910);
FORCEPROP 2 LASTPIN (450 3850) $PN 245
J 0
(460 3860);
DISPLAY 0.617021 (460 3860);
PAINT ORANGE (460 3860);
FORCEPROP 2 LASTPIN (450 3800) $PN 244
J 0
(460 3810);
DISPLAY 0.617021 (460 3810);
PAINT ORANGE (460 3810);
FORCEPROP 2 LASTPIN (450 3750) $PN 186
J 0
(460 3760);
DISPLAY 0.617021 (460 3760);
PAINT ORANGE (460 3760);
FORCEPROP 2 LASTPIN (450 3700) $PN 185
J 0
(460 3710);
DISPLAY 0.617021 (460 3710);
PAINT ORANGE (460 3710);
FORCEPROP 2 LASTPIN (450 3650) $PN 175
J 0
(460 3660);
DISPLAY 0.617021 (460 3660);
PAINT ORANGE (460 3660);
FORCEPROP 2 LASTPIN (450 3600) $PN 174
J 0
(460 3610);
DISPLAY 0.617021 (460 3610);
PAINT ORANGE (460 3610);
FORCEPROP 2 LASTPIN (450 3550) $PN 164
J 0
(460 3560);
DISPLAY 0.617021 (460 3560);
PAINT ORANGE (460 3560);
FORCEPROP 2 LASTPIN (450 3500) $PN 163
J 0
(460 3510);
DISPLAY 0.617021 (460 3510);
PAINT ORANGE (460 3510);
FORCEPROP 2 LASTPIN (450 3450) $PN 153
J 0
(460 3460);
DISPLAY 0.617021 (460 3460);
PAINT ORANGE (460 3460);
FORCEPROP 2 LASTPIN (450 3400) $PN 152
J 0
(460 3410);
DISPLAY 0.617021 (460 3410);
PAINT ORANGE (460 3410);
FORCEPROP 1 LAST PACK_TYPE PIP
J 0
(-400 5450);
PAINT SKYBLUE (-400 5450);
DISPLAY INVISIBLE (-400 5450);
FORCEPROP 2 LAST BOM_COST MEM
J 0
(0 4300);
PAINT ORANGE (0 4300);
DISPLAY INVISIBLE (0 4300);
FORCEPROP 2 LAST CDS_LIB mstr_sconn
J 0
(0 4300);
PAINT ORANGE (0 4300);
DISPLAY INVISIBLE (0 4300);
FORCEPROP 2 LAST SEC_TYPE PIP
J 0
(-400 5450);
DISPLAY 1.021277 (-400 5450);
PAINT ORANGE (-400 5450);
DISPLAY INVISIBLE (-400 5450);
FORCEPROP 2 LAST SEC 2
J 0
(-400 5450);
DISPLAY 0.680851 (-400 5450);
PAINT MONO (-400 5450);
DISPLAY INVISIBLE (-400 5450);
FORCEPROP 2 LAST CDS_LOCATION J6U2
J 0
(-400 5400);
DISPLAY 0.617021 (-400 5400);
PAINT AQUA (-400 5400);
DISPLAY INVISIBLE (-400 5400);
FORCEPROP 1 LAST PATH I61
J 0
(0 5350);
PAINT GREEN (0 5350);
DISPLAY INVISIBLE (0 5350);
FORCEPROP 2 LAST ROOM DDR4_CH_C1
J 0
(-400 5500);
PAINT ORANGE (-400 5500);
DISPLAY INVISIBLE (-400 5500);
FORCEADD TAP..6
R 2
(-1650 4000);
FORCEPROP 3 LASTPIN (-1700 4000) SIG_NAME M_C_DQ<46>
J 0
(-1690 4010);
DISPLAY 0.659574 (-1690 4010);
PAINT MONO (-1690 4010);
DISPLAY INVISIBLE (-1690 4010);
FORCEPROP 1 LASTPIN (-1700 4000) BN 46
J 2
(-1650 4010);
DISPLAY 0.617021 (-1650 4010);
PAINT PINK (-1650 4010);
FORCEPROP 2 LAST CDS_LIB mstr_standard
J 2
(-1650 4000);
DISPLAY 0.787234 (-1650 4000);
PAINT MONO (-1650 4000);
DISPLAY INVISIBLE (-1650 4000);
FORCEPROP 1 LAST BODY_TYPE PLUMBING
J 2
(-1650 3950);
DISPLAY 1.234043 (-1650 3950);
PAINT GREEN (-1650 3950);
DISPLAY INVISIBLE (-1650 3950);
FORCEPROP 1 LAST HDL_TAP TRUE
J 2
(-1975 3875);
DISPLAY 1.234043 (-1975 3875);
PAINT GREEN (-1975 3875);
DISPLAY INVISIBLE (-1975 3875);
FORCEPROP 1 LAST PATH I62
J 2
(-1650 4000);
DISPLAY 0.936170 (-1650 4000);
PAINT GREEN (-1650 4000);
DISPLAY INVISIBLE (-1650 4000);
FORCEADD TAP..6
R 2
(-1650 4050);
FORCEPROP 3 LASTPIN (-1700 4050) SIG_NAME M_C_DQ<47>
J 0
(-1690 4060);
DISPLAY 0.659574 (-1690 4060);
PAINT MONO (-1690 4060);
DISPLAY INVISIBLE (-1690 4060);
FORCEPROP 1 LASTPIN (-1700 4050) BN 47
J 2
(-1650 4060);
DISPLAY 0.617021 (-1650 4060);
PAINT PINK (-1650 4060);
FORCEPROP 2 LAST CDS_LIB mstr_standard
J 2
(-1650 4050);
DISPLAY 0.787234 (-1650 4050);
PAINT MONO (-1650 4050);
DISPLAY INVISIBLE (-1650 4050);
FORCEPROP 1 LAST BODY_TYPE PLUMBING
J 2
(-1650 4000);
DISPLAY 1.234043 (-1650 4000);
PAINT GREEN (-1650 4000);
DISPLAY INVISIBLE (-1650 4000);
FORCEPROP 1 LAST HDL_TAP TRUE
J 2
(-1975 3925);
DISPLAY 1.234043 (-1975 3925);
PAINT GREEN (-1975 3925);
DISPLAY INVISIBLE (-1975 3925);
FORCEPROP 1 LAST PATH I63
J 2
(-1650 4050);
DISPLAY 0.936170 (-1650 4050);
PAINT GREEN (-1650 4050);
DISPLAY INVISIBLE (-1650 4050);
FORCEADD TAP..6
R 2
(-1650 4100);
FORCEPROP 3 LASTPIN (-1700 4100) SIG_NAME M_C_DQ<48>
J 0
(-1690 4110);
DISPLAY 0.659574 (-1690 4110);
PAINT MONO (-1690 4110);
DISPLAY INVISIBLE (-1690 4110);
FORCEPROP 1 LASTPIN (-1700 4100) BN 48
J 2
(-1650 4110);
DISPLAY 0.617021 (-1650 4110);
PAINT PINK (-1650 4110);
FORCEPROP 2 LAST CDS_LIB mstr_standard
J 2
(-1650 4100);
DISPLAY 0.787234 (-1650 4100);
PAINT MONO (-1650 4100);
DISPLAY INVISIBLE (-1650 4100);
FORCEPROP 1 LAST BODY_TYPE PLUMBING
J 2
(-1650 4050);
DISPLAY 1.234043 (-1650 4050);
PAINT GREEN (-1650 4050);
DISPLAY INVISIBLE (-1650 4050);
FORCEPROP 1 LAST HDL_TAP TRUE
J 2
(-1975 3975);
DISPLAY 1.234043 (-1975 3975);
PAINT GREEN (-1975 3975);
DISPLAY INVISIBLE (-1975 3975);
FORCEPROP 1 LAST PATH I64
J 2
(-1650 4100);
DISPLAY 0.936170 (-1650 4100);
PAINT GREEN (-1650 4100);
DISPLAY INVISIBLE (-1650 4100);
FORCEADD TAP..6
R 2
(-1650 3950);
FORCEPROP 3 LASTPIN (-1700 3950) SIG_NAME M_C_DQ<45>
J 0
(-1690 3960);
DISPLAY 0.659574 (-1690 3960);
PAINT MONO (-1690 3960);
DISPLAY INVISIBLE (-1690 3960);
FORCEPROP 1 LASTPIN (-1700 3950) BN 45
J 2
(-1650 3960);
DISPLAY 0.617021 (-1650 3960);
PAINT PINK (-1650 3960);
FORCEPROP 2 LAST CDS_LIB mstr_standard
J 2
(-1650 3950);
DISPLAY 0.787234 (-1650 3950);
PAINT MONO (-1650 3950);
DISPLAY INVISIBLE (-1650 3950);
FORCEPROP 1 LAST BODY_TYPE PLUMBING
J 2
(-1650 3900);
DISPLAY 1.234043 (-1650 3900);
PAINT GREEN (-1650 3900);
DISPLAY INVISIBLE (-1650 3900);
FORCEPROP 1 LAST HDL_TAP TRUE
J 2
(-1975 3825);
DISPLAY 1.234043 (-1975 3825);
PAINT GREEN (-1975 3825);
DISPLAY INVISIBLE (-1975 3825);
FORCEPROP 1 LAST PATH I65
J 2
(-1650 3950);
DISPLAY 0.936170 (-1650 3950);
PAINT GREEN (-1650 3950);
DISPLAY INVISIBLE (-1650 3950);
FORCEADD TAP..6
R 2
(-1650 3900);
FORCEPROP 3 LASTPIN (-1700 3900) SIG_NAME M_C_DQ<44>
J 0
(-1690 3910);
DISPLAY 0.659574 (-1690 3910);
PAINT MONO (-1690 3910);
DISPLAY INVISIBLE (-1690 3910);
FORCEPROP 1 LASTPIN (-1700 3900) BN 44
J 2
(-1650 3910);
DISPLAY 0.617021 (-1650 3910);
PAINT PINK (-1650 3910);
FORCEPROP 2 LAST CDS_LIB mstr_standard
J 2
(-1650 3900);
DISPLAY 0.787234 (-1650 3900);
PAINT MONO (-1650 3900);
DISPLAY INVISIBLE (-1650 3900);
FORCEPROP 1 LAST BODY_TYPE PLUMBING
J 2
(-1650 3850);
DISPLAY 1.234043 (-1650 3850);
PAINT GREEN (-1650 3850);
DISPLAY INVISIBLE (-1650 3850);
FORCEPROP 1 LAST HDL_TAP TRUE
J 2
(-1975 3775);
DISPLAY 1.234043 (-1975 3775);
PAINT GREEN (-1975 3775);
DISPLAY INVISIBLE (-1975 3775);
FORCEPROP 1 LAST PATH I66
J 2
(-1650 3900);
DISPLAY 0.936170 (-1650 3900);
PAINT GREEN (-1650 3900);
DISPLAY INVISIBLE (-1650 3900);
FORCEADD TAP..6
R 2
(-1650 3850);
FORCEPROP 3 LASTPIN (-1700 3850) SIG_NAME M_C_DQ<43>
J 0
(-1690 3860);
DISPLAY 0.659574 (-1690 3860);
PAINT MONO (-1690 3860);
DISPLAY INVISIBLE (-1690 3860);
FORCEPROP 1 LASTPIN (-1700 3850) BN 43
J 2
(-1650 3860);
DISPLAY 0.617021 (-1650 3860);
PAINT PINK (-1650 3860);
FORCEPROP 2 LAST CDS_LIB mstr_standard
J 2
(-1650 3850);
DISPLAY 0.787234 (-1650 3850);
PAINT MONO (-1650 3850);
DISPLAY INVISIBLE (-1650 3850);
FORCEPROP 1 LAST BODY_TYPE PLUMBING
J 2
(-1650 3800);
DISPLAY 1.234043 (-1650 3800);
PAINT GREEN (-1650 3800);
DISPLAY INVISIBLE (-1650 3800);
FORCEPROP 1 LAST HDL_TAP TRUE
J 2
(-1975 3725);
DISPLAY 1.234043 (-1975 3725);
PAINT GREEN (-1975 3725);
DISPLAY INVISIBLE (-1975 3725);
FORCEPROP 1 LAST PATH I67
J 2
(-1650 3850);
DISPLAY 0.936170 (-1650 3850);
PAINT GREEN (-1650 3850);
DISPLAY INVISIBLE (-1650 3850);
FORCEADD TAP..6
R 2
(-1650 3800);
FORCEPROP 3 LASTPIN (-1700 3800) SIG_NAME M_C_DQ<42>
J 0
(-1690 3810);
DISPLAY 0.659574 (-1690 3810);
PAINT MONO (-1690 3810);
DISPLAY INVISIBLE (-1690 3810);
FORCEPROP 1 LASTPIN (-1700 3800) BN 42
J 2
(-1650 3810);
DISPLAY 0.617021 (-1650 3810);
PAINT PINK (-1650 3810);
FORCEPROP 2 LAST CDS_LIB mstr_standard
J 2
(-1650 3800);
DISPLAY 0.787234 (-1650 3800);
PAINT MONO (-1650 3800);
DISPLAY INVISIBLE (-1650 3800);
FORCEPROP 1 LAST BODY_TYPE PLUMBING
J 2
(-1650 3750);
DISPLAY 1.234043 (-1650 3750);
PAINT GREEN (-1650 3750);
DISPLAY INVISIBLE (-1650 3750);
FORCEPROP 1 LAST HDL_TAP TRUE
J 2
(-1975 3675);
DISPLAY 1.234043 (-1975 3675);
PAINT GREEN (-1975 3675);
DISPLAY INVISIBLE (-1975 3675);
FORCEPROP 1 LAST PATH I68
J 2
(-1650 3800);
DISPLAY 0.936170 (-1650 3800);
PAINT GREEN (-1650 3800);
DISPLAY INVISIBLE (-1650 3800);
FORCEADD TAP..6
R 2
(-1650 3750);
FORCEPROP 3 LASTPIN (-1700 3750) SIG_NAME M_C_DQ<41>
J 0
(-1690 3760);
DISPLAY 0.659574 (-1690 3760);
PAINT MONO (-1690 3760);
DISPLAY INVISIBLE (-1690 3760);
FORCEPROP 1 LASTPIN (-1700 3750) BN 41
J 2
(-1650 3760);
DISPLAY 0.617021 (-1650 3760);
PAINT PINK (-1650 3760);
FORCEPROP 2 LAST CDS_LIB mstr_standard
J 2
(-1650 3750);
DISPLAY 0.787234 (-1650 3750);
PAINT MONO (-1650 3750);
DISPLAY INVISIBLE (-1650 3750);
FORCEPROP 1 LAST BODY_TYPE PLUMBING
J 2
(-1650 3700);
DISPLAY 1.234043 (-1650 3700);
PAINT GREEN (-1650 3700);
DISPLAY INVISIBLE (-1650 3700);
FORCEPROP 1 LAST HDL_TAP TRUE
J 2
(-1975 3625);
DISPLAY 1.234043 (-1975 3625);
PAINT GREEN (-1975 3625);
DISPLAY INVISIBLE (-1975 3625);
FORCEPROP 1 LAST PATH I69
J 2
(-1650 3750);
DISPLAY 0.936170 (-1650 3750);
PAINT GREEN (-1650 3750);
DISPLAY INVISIBLE (-1650 3750);
FORCEADD TAP..6
R 2
(900 5000);
FORCEPROP 3 LASTPIN (850 5000) SIG_NAME M_C_DQS_DN<16>
J 0
(860 5010);
DISPLAY 0.659574 (860 5010);
PAINT MONO (860 5010);
DISPLAY INVISIBLE (860 5010);
FORCEPROP 1 LASTPIN (850 5000) BN 16
J 2
(900 5010);
DISPLAY 0.617021 (900 5010);
PAINT PINK (900 5010);
FORCEPROP 2 LAST CDS_LIB mstr_standard
J 0
(900 5000);
DISPLAY 0.787234 (900 5000);
PAINT MONO (900 5000);
DISPLAY INVISIBLE (900 5000);
FORCEPROP 1 LAST BODY_TYPE PLUMBING
J 2
(900 4950);
DISPLAY 1.234043 (900 4950);
PAINT GREEN (900 4950);
DISPLAY INVISIBLE (900 4950);
FORCEPROP 1 LAST HDL_TAP TRUE
J 2
(575 4875);
DISPLAY 1.234043 (575 4875);
PAINT GREEN (575 4875);
DISPLAY INVISIBLE (575 4875);
FORCEPROP 1 LAST PATH I7
J 2
(900 5000);
DISPLAY 0.936170 (900 5000);
PAINT GREEN (900 5000);
DISPLAY INVISIBLE (900 5000);
FORCEADD TAP..6
R 2
(-1650 3650);
FORCEPROP 3 LASTPIN (-1700 3650) SIG_NAME M_C_DQ<39>
J 0
(-1690 3660);
DISPLAY 0.659574 (-1690 3660);
PAINT MONO (-1690 3660);
DISPLAY INVISIBLE (-1690 3660);
FORCEPROP 1 LASTPIN (-1700 3650) BN 39
J 2
(-1650 3660);
DISPLAY 0.617021 (-1650 3660);
PAINT PINK (-1650 3660);
FORCEPROP 2 LAST CDS_LIB mstr_standard
J 2
(-1650 3650);
DISPLAY 0.787234 (-1650 3650);
PAINT MONO (-1650 3650);
DISPLAY INVISIBLE (-1650 3650);
FORCEPROP 1 LAST BODY_TYPE PLUMBING
J 2
(-1650 3600);
DISPLAY 1.234043 (-1650 3600);
PAINT GREEN (-1650 3600);
DISPLAY INVISIBLE (-1650 3600);
FORCEPROP 1 LAST HDL_TAP TRUE
J 2
(-1975 3525);
DISPLAY 1.234043 (-1975 3525);
PAINT GREEN (-1975 3525);
DISPLAY INVISIBLE (-1975 3525);
FORCEPROP 1 LAST PATH I70
J 2
(-1650 3650);
DISPLAY 0.936170 (-1650 3650);
PAINT GREEN (-1650 3650);
DISPLAY INVISIBLE (-1650 3650);
FORCEADD TAP..6
R 2
(-1650 3700);
FORCEPROP 3 LASTPIN (-1700 3700) SIG_NAME M_C_DQ<40>
J 0
(-1690 3710);
DISPLAY 0.659574 (-1690 3710);
PAINT MONO (-1690 3710);
DISPLAY INVISIBLE (-1690 3710);
FORCEPROP 1 LASTPIN (-1700 3700) BN 40
J 2
(-1650 3710);
DISPLAY 0.617021 (-1650 3710);
PAINT PINK (-1650 3710);
FORCEPROP 2 LAST CDS_LIB mstr_standard
J 2
(-1650 3700);
DISPLAY 0.787234 (-1650 3700);
PAINT MONO (-1650 3700);
DISPLAY INVISIBLE (-1650 3700);
FORCEPROP 1 LAST BODY_TYPE PLUMBING
J 2
(-1650 3650);
DISPLAY 1.234043 (-1650 3650);
PAINT GREEN (-1650 3650);
DISPLAY INVISIBLE (-1650 3650);
FORCEPROP 1 LAST HDL_TAP TRUE
J 2
(-1975 3575);
DISPLAY 1.234043 (-1975 3575);
PAINT GREEN (-1975 3575);
DISPLAY INVISIBLE (-1975 3575);
FORCEPROP 1 LAST PATH I71
J 2
(-1650 3700);
DISPLAY 0.936170 (-1650 3700);
PAINT GREEN (-1650 3700);
DISPLAY INVISIBLE (-1650 3700);
FORCEADD TAP..6
R 2
(-1650 3500);
FORCEPROP 3 LASTPIN (-1700 3500) SIG_NAME M_C_DQ<36>
J 0
(-1690 3510);
DISPLAY 0.659574 (-1690 3510);
PAINT MONO (-1690 3510);
DISPLAY INVISIBLE (-1690 3510);
FORCEPROP 1 LASTPIN (-1700 3500) BN 36
J 2
(-1650 3510);
DISPLAY 0.617021 (-1650 3510);
PAINT PINK (-1650 3510);
FORCEPROP 2 LAST CDS_LIB mstr_standard
J 2
(-1650 3500);
DISPLAY 0.787234 (-1650 3500);
PAINT MONO (-1650 3500);
DISPLAY INVISIBLE (-1650 3500);
FORCEPROP 1 LAST BODY_TYPE PLUMBING
J 2
(-1650 3450);
DISPLAY 1.234043 (-1650 3450);
PAINT GREEN (-1650 3450);
DISPLAY INVISIBLE (-1650 3450);
FORCEPROP 1 LAST HDL_TAP TRUE
J 2
(-1975 3375);
DISPLAY 1.234043 (-1975 3375);
PAINT GREEN (-1975 3375);
DISPLAY INVISIBLE (-1975 3375);
FORCEPROP 1 LAST PATH I72
J 2
(-1650 3500);
DISPLAY 0.936170 (-1650 3500);
PAINT GREEN (-1650 3500);
DISPLAY INVISIBLE (-1650 3500);
FORCEADD TAP..6
R 2
(-1650 3550);
FORCEPROP 3 LASTPIN (-1700 3550) SIG_NAME M_C_DQ<37>
J 0
(-1690 3560);
DISPLAY 0.659574 (-1690 3560);
PAINT MONO (-1690 3560);
DISPLAY INVISIBLE (-1690 3560);
FORCEPROP 1 LASTPIN (-1700 3550) BN 37
J 2
(-1650 3560);
DISPLAY 0.617021 (-1650 3560);
PAINT PINK (-1650 3560);
FORCEPROP 2 LAST CDS_LIB mstr_standard
J 2
(-1650 3550);
DISPLAY 0.787234 (-1650 3550);
PAINT MONO (-1650 3550);
DISPLAY INVISIBLE (-1650 3550);
FORCEPROP 1 LAST BODY_TYPE PLUMBING
J 2
(-1650 3500);
DISPLAY 1.234043 (-1650 3500);
PAINT GREEN (-1650 3500);
DISPLAY INVISIBLE (-1650 3500);
FORCEPROP 1 LAST HDL_TAP TRUE
J 2
(-1975 3425);
DISPLAY 1.234043 (-1975 3425);
PAINT GREEN (-1975 3425);
DISPLAY INVISIBLE (-1975 3425);
FORCEPROP 1 LAST PATH I73
J 2
(-1650 3550);
DISPLAY 0.936170 (-1650 3550);
PAINT GREEN (-1650 3550);
DISPLAY INVISIBLE (-1650 3550);
FORCEADD TAP..6
R 2
(-1650 3600);
FORCEPROP 3 LASTPIN (-1700 3600) SIG_NAME M_C_DQ<38>
J 0
(-1690 3610);
DISPLAY 0.659574 (-1690 3610);
PAINT MONO (-1690 3610);
DISPLAY INVISIBLE (-1690 3610);
FORCEPROP 1 LASTPIN (-1700 3600) BN 38
J 2
(-1650 3610);
DISPLAY 0.617021 (-1650 3610);
PAINT PINK (-1650 3610);
FORCEPROP 2 LAST CDS_LIB mstr_standard
J 2
(-1650 3600);
DISPLAY 0.787234 (-1650 3600);
PAINT MONO (-1650 3600);
DISPLAY INVISIBLE (-1650 3600);
FORCEPROP 1 LAST BODY_TYPE PLUMBING
J 2
(-1650 3550);
DISPLAY 1.234043 (-1650 3550);
PAINT GREEN (-1650 3550);
DISPLAY INVISIBLE (-1650 3550);
FORCEPROP 1 LAST HDL_TAP TRUE
J 2
(-1975 3475);
DISPLAY 1.234043 (-1975 3475);
PAINT GREEN (-1975 3475);
DISPLAY INVISIBLE (-1975 3475);
FORCEPROP 1 LAST PATH I74
J 2
(-1650 3600);
DISPLAY 0.936170 (-1650 3600);
PAINT GREEN (-1650 3600);
DISPLAY INVISIBLE (-1650 3600);
FORCEADD TAP..6
R 2
(-1650 3400);
FORCEPROP 3 LASTPIN (-1700 3400) SIG_NAME M_C_DQ<34>
J 0
(-1690 3410);
DISPLAY 0.659574 (-1690 3410);
PAINT MONO (-1690 3410);
DISPLAY INVISIBLE (-1690 3410);
FORCEPROP 1 LASTPIN (-1700 3400) BN 34
J 2
(-1650 3410);
DISPLAY 0.617021 (-1650 3410);
PAINT PINK (-1650 3410);
FORCEPROP 2 LAST CDS_LIB mstr_standard
J 2
(-1650 3400);
DISPLAY 0.787234 (-1650 3400);
PAINT MONO (-1650 3400);
DISPLAY INVISIBLE (-1650 3400);
FORCEPROP 1 LAST BODY_TYPE PLUMBING
J 2
(-1650 3350);
DISPLAY 1.234043 (-1650 3350);
PAINT GREEN (-1650 3350);
DISPLAY INVISIBLE (-1650 3350);
FORCEPROP 1 LAST HDL_TAP TRUE
J 2
(-1975 3275);
DISPLAY 1.234043 (-1975 3275);
PAINT GREEN (-1975 3275);
DISPLAY INVISIBLE (-1975 3275);
FORCEPROP 1 LAST PATH I75
J 2
(-1650 3400);
DISPLAY 0.936170 (-1650 3400);
PAINT GREEN (-1650 3400);
DISPLAY INVISIBLE (-1650 3400);
FORCEADD TAP..6
R 2
(-1650 3450);
FORCEPROP 3 LASTPIN (-1700 3450) SIG_NAME M_C_DQ<35>
J 0
(-1690 3460);
DISPLAY 0.659574 (-1690 3460);
PAINT MONO (-1690 3460);
DISPLAY INVISIBLE (-1690 3460);
FORCEPROP 1 LASTPIN (-1700 3450) BN 35
J 2
(-1650 3460);
DISPLAY 0.617021 (-1650 3460);
PAINT PINK (-1650 3460);
FORCEPROP 2 LAST CDS_LIB mstr_standard
J 2
(-1650 3450);
DISPLAY 0.787234 (-1650 3450);
PAINT MONO (-1650 3450);
DISPLAY INVISIBLE (-1650 3450);
FORCEPROP 1 LAST BODY_TYPE PLUMBING
J 2
(-1650 3400);
DISPLAY 1.234043 (-1650 3400);
PAINT GREEN (-1650 3400);
DISPLAY INVISIBLE (-1650 3400);
FORCEPROP 1 LAST HDL_TAP TRUE
J 2
(-1975 3325);
DISPLAY 1.234043 (-1975 3325);
PAINT GREEN (-1975 3325);
DISPLAY INVISIBLE (-1975 3325);
FORCEPROP 1 LAST PATH I76
J 2
(-1650 3450);
DISPLAY 0.936170 (-1650 3450);
PAINT GREEN (-1650 3450);
DISPLAY INVISIBLE (-1650 3450);
FORCEADD TAP..6
R 2
(-1650 3350);
FORCEPROP 3 LASTPIN (-1700 3350) SIG_NAME M_C_DQ<33>
J 0
(-1690 3360);
DISPLAY 0.659574 (-1690 3360);
PAINT MONO (-1690 3360);
DISPLAY INVISIBLE (-1690 3360);
FORCEPROP 1 LASTPIN (-1700 3350) BN 33
J 2
(-1650 3360);
DISPLAY 0.617021 (-1650 3360);
PAINT PINK (-1650 3360);
FORCEPROP 2 LAST CDS_LIB mstr_standard
J 2
(-1650 3350);
DISPLAY 0.787234 (-1650 3350);
PAINT MONO (-1650 3350);
DISPLAY INVISIBLE (-1650 3350);
FORCEPROP 1 LAST BODY_TYPE PLUMBING
J 2
(-1650 3300);
DISPLAY 1.234043 (-1650 3300);
PAINT GREEN (-1650 3300);
DISPLAY INVISIBLE (-1650 3300);
FORCEPROP 1 LAST HDL_TAP TRUE
J 2
(-1975 3225);
DISPLAY 1.234043 (-1975 3225);
PAINT GREEN (-1975 3225);
DISPLAY INVISIBLE (-1975 3225);
FORCEPROP 1 LAST PATH I77
J 2
(-1650 3350);
DISPLAY 0.936170 (-1650 3350);
PAINT GREEN (-1650 3350);
DISPLAY INVISIBLE (-1650 3350);
FORCEADD TAP..6
R 2
(-1650 3300);
FORCEPROP 3 LASTPIN (-1700 3300) SIG_NAME M_C_DQ<32>
J 0
(-1690 3310);
DISPLAY 0.659574 (-1690 3310);
PAINT MONO (-1690 3310);
DISPLAY INVISIBLE (-1690 3310);
FORCEPROP 1 LASTPIN (-1700 3300) BN 32
J 2
(-1650 3310);
DISPLAY 0.617021 (-1650 3310);
PAINT PINK (-1650 3310);
FORCEPROP 2 LAST CDS_LIB mstr_standard
J 2
(-1650 3300);
DISPLAY 0.787234 (-1650 3300);
PAINT MONO (-1650 3300);
DISPLAY INVISIBLE (-1650 3300);
FORCEPROP 1 LAST BODY_TYPE PLUMBING
J 2
(-1650 3250);
DISPLAY 1.234043 (-1650 3250);
PAINT GREEN (-1650 3250);
DISPLAY INVISIBLE (-1650 3250);
FORCEPROP 1 LAST HDL_TAP TRUE
J 2
(-1975 3175);
DISPLAY 1.234043 (-1975 3175);
PAINT GREEN (-1975 3175);
DISPLAY INVISIBLE (-1975 3175);
FORCEPROP 1 LAST PATH I78
J 2
(-1650 3300);
DISPLAY 0.936170 (-1650 3300);
PAINT GREEN (-1650 3300);
DISPLAY INVISIBLE (-1650 3300);
FORCEADD TAP..6
R 2
(-1650 3250);
FORCEPROP 3 LASTPIN (-1700 3250) SIG_NAME M_C_DQ<31>
J 0
(-1690 3260);
DISPLAY 0.659574 (-1690 3260);
PAINT MONO (-1690 3260);
DISPLAY INVISIBLE (-1690 3260);
FORCEPROP 1 LASTPIN (-1700 3250) BN 31
J 2
(-1650 3260);
DISPLAY 0.617021 (-1650 3260);
PAINT PINK (-1650 3260);
FORCEPROP 2 LAST CDS_LIB mstr_standard
J 2
(-1650 3250);
DISPLAY 0.787234 (-1650 3250);
PAINT MONO (-1650 3250);
DISPLAY INVISIBLE (-1650 3250);
FORCEPROP 1 LAST BODY_TYPE PLUMBING
J 2
(-1650 3200);
DISPLAY 1.234043 (-1650 3200);
PAINT GREEN (-1650 3200);
DISPLAY INVISIBLE (-1650 3200);
FORCEPROP 1 LAST HDL_TAP TRUE
J 2
(-1975 3125);
DISPLAY 1.234043 (-1975 3125);
PAINT GREEN (-1975 3125);
DISPLAY INVISIBLE (-1975 3125);
FORCEPROP 1 LAST PATH I79
J 2
(-1650 3250);
DISPLAY 0.936170 (-1650 3250);
PAINT GREEN (-1650 3250);
DISPLAY INVISIBLE (-1650 3250);
FORCEADD TAP..6
R 2
(900 4800);
FORCEPROP 3 LASTPIN (850 4800) SIG_NAME M_C_DQS_DN<14>
J 0
(860 4810);
DISPLAY 0.659574 (860 4810);
PAINT MONO (860 4810);
DISPLAY INVISIBLE (860 4810);
FORCEPROP 1 LASTPIN (850 4800) BN 14
J 2
(900 4810);
DISPLAY 0.617021 (900 4810);
PAINT PINK (900 4810);
FORCEPROP 2 LAST CDS_LIB mstr_standard
J 0
(900 4800);
DISPLAY 0.787234 (900 4800);
PAINT MONO (900 4800);
DISPLAY INVISIBLE (900 4800);
FORCEPROP 1 LAST BODY_TYPE PLUMBING
J 2
(900 4750);
DISPLAY 1.234043 (900 4750);
PAINT GREEN (900 4750);
DISPLAY INVISIBLE (900 4750);
FORCEPROP 1 LAST HDL_TAP TRUE
J 2
(575 4675);
DISPLAY 1.234043 (575 4675);
PAINT GREEN (575 4675);
DISPLAY INVISIBLE (575 4675);
FORCEPROP 1 LAST PATH I8
J 2
(900 4800);
DISPLAY 0.936170 (900 4800);
PAINT GREEN (900 4800);
DISPLAY INVISIBLE (900 4800);
FORCEADD TAP..6
R 2
(-1650 3100);
FORCEPROP 3 LASTPIN (-1700 3100) SIG_NAME M_C_DQ<28>
J 0
(-1690 3110);
DISPLAY 0.659574 (-1690 3110);
PAINT MONO (-1690 3110);
DISPLAY INVISIBLE (-1690 3110);
FORCEPROP 1 LASTPIN (-1700 3100) BN 28
J 2
(-1650 3110);
DISPLAY 0.617021 (-1650 3110);
PAINT PINK (-1650 3110);
FORCEPROP 2 LAST CDS_LIB mstr_standard
J 2
(-1650 3100);
DISPLAY 0.787234 (-1650 3100);
PAINT MONO (-1650 3100);
DISPLAY INVISIBLE (-1650 3100);
FORCEPROP 1 LAST BODY_TYPE PLUMBING
J 2
(-1650 3050);
DISPLAY 1.234043 (-1650 3050);
PAINT GREEN (-1650 3050);
DISPLAY INVISIBLE (-1650 3050);
FORCEPROP 1 LAST HDL_TAP TRUE
J 2
(-1975 2975);
DISPLAY 1.234043 (-1975 2975);
PAINT GREEN (-1975 2975);
DISPLAY INVISIBLE (-1975 2975);
FORCEPROP 1 LAST PATH I80
J 2
(-1650 3100);
DISPLAY 0.936170 (-1650 3100);
PAINT GREEN (-1650 3100);
DISPLAY INVISIBLE (-1650 3100);
FORCEADD TAP..6
R 2
(-1650 3150);
FORCEPROP 3 LASTPIN (-1700 3150) SIG_NAME M_C_DQ<29>
J 0
(-1690 3160);
DISPLAY 0.659574 (-1690 3160);
PAINT MONO (-1690 3160);
DISPLAY INVISIBLE (-1690 3160);
FORCEPROP 1 LASTPIN (-1700 3150) BN 29
J 2
(-1650 3160);
DISPLAY 0.617021 (-1650 3160);
PAINT PINK (-1650 3160);
FORCEPROP 2 LAST CDS_LIB mstr_standard
J 2
(-1650 3150);
DISPLAY 0.787234 (-1650 3150);
PAINT MONO (-1650 3150);
DISPLAY INVISIBLE (-1650 3150);
FORCEPROP 1 LAST BODY_TYPE PLUMBING
J 2
(-1650 3100);
DISPLAY 1.234043 (-1650 3100);
PAINT GREEN (-1650 3100);
DISPLAY INVISIBLE (-1650 3100);
FORCEPROP 1 LAST HDL_TAP TRUE
J 2
(-1975 3025);
DISPLAY 1.234043 (-1975 3025);
PAINT GREEN (-1975 3025);
DISPLAY INVISIBLE (-1975 3025);
FORCEPROP 1 LAST PATH I81
J 2
(-1650 3150);
DISPLAY 0.936170 (-1650 3150);
PAINT GREEN (-1650 3150);
DISPLAY INVISIBLE (-1650 3150);
FORCEADD TAP..6
R 2
(-1650 3200);
FORCEPROP 3 LASTPIN (-1700 3200) SIG_NAME M_C_DQ<30>
J 0
(-1690 3210);
DISPLAY 0.659574 (-1690 3210);
PAINT MONO (-1690 3210);
DISPLAY INVISIBLE (-1690 3210);
FORCEPROP 1 LASTPIN (-1700 3200) BN 30
J 2
(-1650 3210);
DISPLAY 0.617021 (-1650 3210);
PAINT PINK (-1650 3210);
FORCEPROP 2 LAST CDS_LIB mstr_standard
J 2
(-1650 3200);
DISPLAY 0.787234 (-1650 3200);
PAINT MONO (-1650 3200);
DISPLAY INVISIBLE (-1650 3200);
FORCEPROP 1 LAST BODY_TYPE PLUMBING
J 2
(-1650 3150);
DISPLAY 1.234043 (-1650 3150);
PAINT GREEN (-1650 3150);
DISPLAY INVISIBLE (-1650 3150);
FORCEPROP 1 LAST HDL_TAP TRUE
J 2
(-1975 3075);
DISPLAY 1.234043 (-1975 3075);
PAINT GREEN (-1975 3075);
DISPLAY INVISIBLE (-1975 3075);
FORCEPROP 1 LAST PATH I82
J 2
(-1650 3200);
DISPLAY 0.936170 (-1650 3200);
PAINT GREEN (-1650 3200);
DISPLAY INVISIBLE (-1650 3200);
FORCEADD TAP..6
R 2
(-1650 3050);
FORCEPROP 3 LASTPIN (-1700 3050) SIG_NAME M_C_DQ<27>
J 0
(-1690 3060);
DISPLAY 0.659574 (-1690 3060);
PAINT MONO (-1690 3060);
DISPLAY INVISIBLE (-1690 3060);
FORCEPROP 1 LASTPIN (-1700 3050) BN 27
J 2
(-1650 3060);
DISPLAY 0.617021 (-1650 3060);
PAINT PINK (-1650 3060);
FORCEPROP 2 LAST CDS_LIB mstr_standard
J 2
(-1650 3050);
DISPLAY 0.787234 (-1650 3050);
PAINT MONO (-1650 3050);
DISPLAY INVISIBLE (-1650 3050);
FORCEPROP 1 LAST BODY_TYPE PLUMBING
J 2
(-1650 3000);
DISPLAY 1.234043 (-1650 3000);
PAINT GREEN (-1650 3000);
DISPLAY INVISIBLE (-1650 3000);
FORCEPROP 1 LAST HDL_TAP TRUE
J 2
(-1975 2925);
DISPLAY 1.234043 (-1975 2925);
PAINT GREEN (-1975 2925);
DISPLAY INVISIBLE (-1975 2925);
FORCEPROP 1 LAST PATH I83
J 2
(-1650 3050);
DISPLAY 0.936170 (-1650 3050);
PAINT GREEN (-1650 3050);
DISPLAY INVISIBLE (-1650 3050);
FORCEADD TAP..6
R 2
(-1650 3000);
FORCEPROP 3 LASTPIN (-1700 3000) SIG_NAME M_C_DQ<26>
J 0
(-1690 3010);
DISPLAY 0.659574 (-1690 3010);
PAINT MONO (-1690 3010);
DISPLAY INVISIBLE (-1690 3010);
FORCEPROP 1 LASTPIN (-1700 3000) BN 26
J 2
(-1650 3010);
DISPLAY 0.617021 (-1650 3010);
PAINT PINK (-1650 3010);
FORCEPROP 2 LAST CDS_LIB mstr_standard
J 2
(-1650 3000);
DISPLAY 0.787234 (-1650 3000);
PAINT MONO (-1650 3000);
DISPLAY INVISIBLE (-1650 3000);
FORCEPROP 1 LAST BODY_TYPE PLUMBING
J 2
(-1650 2950);
DISPLAY 1.234043 (-1650 2950);
PAINT GREEN (-1650 2950);
DISPLAY INVISIBLE (-1650 2950);
FORCEPROP 1 LAST HDL_TAP TRUE
J 2
(-1975 2875);
DISPLAY 1.234043 (-1975 2875);
PAINT GREEN (-1975 2875);
DISPLAY INVISIBLE (-1975 2875);
FORCEPROP 1 LAST PATH I84
J 2
(-1650 3000);
DISPLAY 0.936170 (-1650 3000);
PAINT GREEN (-1650 3000);
DISPLAY INVISIBLE (-1650 3000);
FORCEADD TAP..6
R 2
(-1650 2850);
FORCEPROP 3 LASTPIN (-1700 2850) SIG_NAME M_C_DQ<23>
J 0
(-1690 2860);
DISPLAY 0.659574 (-1690 2860);
PAINT MONO (-1690 2860);
DISPLAY INVISIBLE (-1690 2860);
FORCEPROP 1 LASTPIN (-1700 2850) BN 23
J 2
(-1650 2860);
DISPLAY 0.617021 (-1650 2860);
PAINT PINK (-1650 2860);
FORCEPROP 2 LAST CDS_LIB mstr_standard
J 2
(-1650 2850);
DISPLAY 0.787234 (-1650 2850);
PAINT MONO (-1650 2850);
DISPLAY INVISIBLE (-1650 2850);
FORCEPROP 1 LAST BODY_TYPE PLUMBING
J 2
(-1650 2800);
DISPLAY 1.234043 (-1650 2800);
PAINT GREEN (-1650 2800);
DISPLAY INVISIBLE (-1650 2800);
FORCEPROP 1 LAST HDL_TAP TRUE
J 2
(-1975 2725);
DISPLAY 1.234043 (-1975 2725);
PAINT GREEN (-1975 2725);
DISPLAY INVISIBLE (-1975 2725);
FORCEPROP 1 LAST PATH I85
J 2
(-1650 2850);
DISPLAY 0.936170 (-1650 2850);
PAINT GREEN (-1650 2850);
DISPLAY INVISIBLE (-1650 2850);
FORCEADD TAP..6
R 2
(-1650 2950);
FORCEPROP 3 LASTPIN (-1700 2950) SIG_NAME M_C_DQ<25>
J 0
(-1690 2960);
DISPLAY 0.659574 (-1690 2960);
PAINT MONO (-1690 2960);
DISPLAY INVISIBLE (-1690 2960);
FORCEPROP 1 LASTPIN (-1700 2950) BN 25
J 2
(-1650 2960);
DISPLAY 0.617021 (-1650 2960);
PAINT PINK (-1650 2960);
FORCEPROP 2 LAST CDS_LIB mstr_standard
J 2
(-1650 2950);
DISPLAY 0.787234 (-1650 2950);
PAINT MONO (-1650 2950);
DISPLAY INVISIBLE (-1650 2950);
FORCEPROP 1 LAST BODY_TYPE PLUMBING
J 2
(-1650 2900);
DISPLAY 1.234043 (-1650 2900);
PAINT GREEN (-1650 2900);
DISPLAY INVISIBLE (-1650 2900);
FORCEPROP 1 LAST HDL_TAP TRUE
J 2
(-1975 2825);
DISPLAY 1.234043 (-1975 2825);
PAINT GREEN (-1975 2825);
DISPLAY INVISIBLE (-1975 2825);
FORCEPROP 1 LAST PATH I86
J 2
(-1650 2950);
DISPLAY 0.936170 (-1650 2950);
PAINT GREEN (-1650 2950);
DISPLAY INVISIBLE (-1650 2950);
FORCEADD TAP..6
R 2
(-1650 2900);
FORCEPROP 3 LASTPIN (-1700 2900) SIG_NAME M_C_DQ<24>
J 0
(-1690 2910);
DISPLAY 0.659574 (-1690 2910);
PAINT MONO (-1690 2910);
DISPLAY INVISIBLE (-1690 2910);
FORCEPROP 1 LASTPIN (-1700 2900) BN 24
J 2
(-1650 2910);
DISPLAY 0.617021 (-1650 2910);
PAINT PINK (-1650 2910);
FORCEPROP 2 LAST CDS_LIB mstr_standard
J 2
(-1650 2900);
DISPLAY 0.787234 (-1650 2900);
PAINT MONO (-1650 2900);
DISPLAY INVISIBLE (-1650 2900);
FORCEPROP 1 LAST BODY_TYPE PLUMBING
J 2
(-1650 2850);
DISPLAY 1.234043 (-1650 2850);
PAINT GREEN (-1650 2850);
DISPLAY INVISIBLE (-1650 2850);
FORCEPROP 1 LAST HDL_TAP TRUE
J 2
(-1975 2775);
DISPLAY 1.234043 (-1975 2775);
PAINT GREEN (-1975 2775);
DISPLAY INVISIBLE (-1975 2775);
FORCEPROP 1 LAST PATH I87
J 2
(-1650 2900);
DISPLAY 0.936170 (-1650 2900);
PAINT GREEN (-1650 2900);
DISPLAY INVISIBLE (-1650 2900);
FORCEADD TAP..6
R 2
(-1650 2750);
FORCEPROP 3 LASTPIN (-1700 2750) SIG_NAME M_C_DQ<21>
J 0
(-1690 2760);
DISPLAY 0.659574 (-1690 2760);
PAINT MONO (-1690 2760);
DISPLAY INVISIBLE (-1690 2760);
FORCEPROP 1 LASTPIN (-1700 2750) BN 21
J 2
(-1650 2760);
DISPLAY 0.617021 (-1650 2760);
PAINT PINK (-1650 2760);
FORCEPROP 2 LAST CDS_LIB mstr_standard
J 2
(-1650 2750);
DISPLAY 0.787234 (-1650 2750);
PAINT MONO (-1650 2750);
DISPLAY INVISIBLE (-1650 2750);
FORCEPROP 1 LAST BODY_TYPE PLUMBING
J 2
(-1650 2700);
DISPLAY 1.234043 (-1650 2700);
PAINT GREEN (-1650 2700);
DISPLAY INVISIBLE (-1650 2700);
FORCEPROP 1 LAST HDL_TAP TRUE
J 2
(-1975 2625);
DISPLAY 1.234043 (-1975 2625);
PAINT GREEN (-1975 2625);
DISPLAY INVISIBLE (-1975 2625);
FORCEPROP 1 LAST PATH I88
J 2
(-1650 2750);
DISPLAY 0.936170 (-1650 2750);
PAINT GREEN (-1650 2750);
DISPLAY INVISIBLE (-1650 2750);
FORCEADD TAP..6
R 2
(-1650 2800);
FORCEPROP 3 LASTPIN (-1700 2800) SIG_NAME M_C_DQ<22>
J 0
(-1690 2810);
DISPLAY 0.659574 (-1690 2810);
PAINT MONO (-1690 2810);
DISPLAY INVISIBLE (-1690 2810);
FORCEPROP 1 LASTPIN (-1700 2800) BN 22
J 2
(-1650 2810);
DISPLAY 0.617021 (-1650 2810);
PAINT PINK (-1650 2810);
FORCEPROP 2 LAST CDS_LIB mstr_standard
J 2
(-1650 2800);
DISPLAY 0.787234 (-1650 2800);
PAINT MONO (-1650 2800);
DISPLAY INVISIBLE (-1650 2800);
FORCEPROP 1 LAST BODY_TYPE PLUMBING
J 2
(-1650 2750);
DISPLAY 1.234043 (-1650 2750);
PAINT GREEN (-1650 2750);
DISPLAY INVISIBLE (-1650 2750);
FORCEPROP 1 LAST HDL_TAP TRUE
J 2
(-1975 2675);
DISPLAY 1.234043 (-1975 2675);
PAINT GREEN (-1975 2675);
DISPLAY INVISIBLE (-1975 2675);
FORCEPROP 1 LAST PATH I89
J 2
(-1650 2800);
DISPLAY 0.936170 (-1650 2800);
PAINT GREEN (-1650 2800);
DISPLAY INVISIBLE (-1650 2800);
FORCEADD TAP..6
R 2
(700 4950);
FORCEPROP 3 LASTPIN (650 4950) SIG_NAME M_C_DQS_DP<15>
J 0
(660 4960);
DISPLAY 0.659574 (660 4960);
PAINT MONO (660 4960);
DISPLAY INVISIBLE (660 4960);
FORCEPROP 1 LASTPIN (650 4950) BN 15
J 2
(700 4960);
DISPLAY 0.617021 (700 4960);
PAINT PINK (700 4960);
FORCEPROP 2 LAST CDS_LIB mstr_standard
J 0
(700 4950);
DISPLAY 0.787234 (700 4950);
PAINT MONO (700 4950);
DISPLAY INVISIBLE (700 4950);
FORCEPROP 1 LAST BODY_TYPE PLUMBING
J 2
(700 4900);
DISPLAY 1.234043 (700 4900);
PAINT GREEN (700 4900);
DISPLAY INVISIBLE (700 4900);
FORCEPROP 1 LAST HDL_TAP TRUE
J 2
(375 4825);
DISPLAY 1.234043 (375 4825);
PAINT WHITE (375 4825);
DISPLAY INVISIBLE (375 4825);
FORCEPROP 1 LAST PATH I9
J 2
(700 4950);
DISPLAY 0.936170 (700 4950);
PAINT GREEN (700 4950);
DISPLAY INVISIBLE (700 4950);
FORCEADD TAP..6
R 2
(-1650 2700);
FORCEPROP 3 LASTPIN (-1700 2700) SIG_NAME M_C_DQ<20>
J 0
(-1690 2710);
DISPLAY 0.659574 (-1690 2710);
PAINT MONO (-1690 2710);
DISPLAY INVISIBLE (-1690 2710);
FORCEPROP 1 LASTPIN (-1700 2700) BN 20
J 2
(-1650 2710);
DISPLAY 0.617021 (-1650 2710);
PAINT PINK (-1650 2710);
FORCEPROP 2 LAST CDS_LIB mstr_standard
J 2
(-1650 2700);
DISPLAY 0.787234 (-1650 2700);
PAINT MONO (-1650 2700);
DISPLAY INVISIBLE (-1650 2700);
FORCEPROP 1 LAST BODY_TYPE PLUMBING
J 2
(-1650 2650);
DISPLAY 1.234043 (-1650 2650);
PAINT GREEN (-1650 2650);
DISPLAY INVISIBLE (-1650 2650);
FORCEPROP 1 LAST HDL_TAP TRUE
J 2
(-1975 2575);
DISPLAY 1.234043 (-1975 2575);
PAINT GREEN (-1975 2575);
DISPLAY INVISIBLE (-1975 2575);
FORCEPROP 1 LAST PATH I90
J 2
(-1650 2700);
DISPLAY 0.936170 (-1650 2700);
PAINT GREEN (-1650 2700);
DISPLAY INVISIBLE (-1650 2700);
FORCEADD TAP..6
R 2
(-1650 2650);
FORCEPROP 3 LASTPIN (-1700 2650) SIG_NAME M_C_DQ<19>
J 0
(-1690 2660);
DISPLAY 0.659574 (-1690 2660);
PAINT MONO (-1690 2660);
DISPLAY INVISIBLE (-1690 2660);
FORCEPROP 1 LASTPIN (-1700 2650) BN 19
J 2
(-1650 2660);
DISPLAY 0.617021 (-1650 2660);
PAINT PINK (-1650 2660);
FORCEPROP 2 LAST CDS_LIB mstr_standard
J 2
(-1650 2650);
DISPLAY 0.787234 (-1650 2650);
PAINT MONO (-1650 2650);
DISPLAY INVISIBLE (-1650 2650);
FORCEPROP 1 LAST BODY_TYPE PLUMBING
J 2
(-1650 2600);
DISPLAY 1.234043 (-1650 2600);
PAINT GREEN (-1650 2600);
DISPLAY INVISIBLE (-1650 2600);
FORCEPROP 1 LAST HDL_TAP TRUE
J 2
(-1975 2525);
DISPLAY 1.234043 (-1975 2525);
PAINT GREEN (-1975 2525);
DISPLAY INVISIBLE (-1975 2525);
FORCEPROP 1 LAST PATH I91
J 2
(-1650 2650);
DISPLAY 0.936170 (-1650 2650);
PAINT GREEN (-1650 2650);
DISPLAY INVISIBLE (-1650 2650);
FORCEADD TAP..6
R 2
(-1650 2600);
FORCEPROP 3 LASTPIN (-1700 2600) SIG_NAME M_C_DQ<18>
J 0
(-1690 2610);
DISPLAY 0.659574 (-1690 2610);
PAINT MONO (-1690 2610);
DISPLAY INVISIBLE (-1690 2610);
FORCEPROP 1 LASTPIN (-1700 2600) BN 18
J 2
(-1650 2610);
DISPLAY 0.617021 (-1650 2610);
PAINT PINK (-1650 2610);
FORCEPROP 2 LAST CDS_LIB mstr_standard
J 2
(-1650 2600);
DISPLAY 0.787234 (-1650 2600);
PAINT MONO (-1650 2600);
DISPLAY INVISIBLE (-1650 2600);
FORCEPROP 1 LAST BODY_TYPE PLUMBING
J 2
(-1650 2550);
DISPLAY 1.234043 (-1650 2550);
PAINT GREEN (-1650 2550);
DISPLAY INVISIBLE (-1650 2550);
FORCEPROP 1 LAST HDL_TAP TRUE
J 2
(-1975 2475);
DISPLAY 1.234043 (-1975 2475);
PAINT GREEN (-1975 2475);
DISPLAY INVISIBLE (-1975 2475);
FORCEPROP 1 LAST PATH I92
J 2
(-1650 2600);
DISPLAY 0.936170 (-1650 2600);
PAINT GREEN (-1650 2600);
DISPLAY INVISIBLE (-1650 2600);
FORCEADD TAP..6
R 2
(-1650 2500);
FORCEPROP 3 LASTPIN (-1700 2500) SIG_NAME M_C_DQ<16>
J 0
(-1690 2510);
DISPLAY 0.659574 (-1690 2510);
PAINT MONO (-1690 2510);
DISPLAY INVISIBLE (-1690 2510);
FORCEPROP 1 LASTPIN (-1700 2500) BN 16
J 2
(-1650 2510);
DISPLAY 0.617021 (-1650 2510);
PAINT PINK (-1650 2510);
FORCEPROP 2 LAST CDS_LIB mstr_standard
J 2
(-1650 2500);
DISPLAY 0.787234 (-1650 2500);
PAINT MONO (-1650 2500);
DISPLAY INVISIBLE (-1650 2500);
FORCEPROP 1 LAST BODY_TYPE PLUMBING
J 2
(-1650 2450);
DISPLAY 1.234043 (-1650 2450);
PAINT GREEN (-1650 2450);
DISPLAY INVISIBLE (-1650 2450);
FORCEPROP 1 LAST HDL_TAP TRUE
J 2
(-1975 2375);
DISPLAY 1.234043 (-1975 2375);
PAINT GREEN (-1975 2375);
DISPLAY INVISIBLE (-1975 2375);
FORCEPROP 1 LAST PATH I93
J 2
(-1650 2500);
DISPLAY 0.936170 (-1650 2500);
PAINT GREEN (-1650 2500);
DISPLAY INVISIBLE (-1650 2500);
FORCEADD TAP..6
R 2
(-1650 2550);
FORCEPROP 3 LASTPIN (-1700 2550) SIG_NAME M_C_DQ<17>
J 0
(-1690 2560);
DISPLAY 0.659574 (-1690 2560);
PAINT MONO (-1690 2560);
DISPLAY INVISIBLE (-1690 2560);
FORCEPROP 1 LASTPIN (-1700 2550) BN 17
J 2
(-1650 2560);
DISPLAY 0.617021 (-1650 2560);
PAINT PINK (-1650 2560);
FORCEPROP 2 LAST CDS_LIB mstr_standard
J 2
(-1650 2550);
DISPLAY 0.787234 (-1650 2550);
PAINT MONO (-1650 2550);
DISPLAY INVISIBLE (-1650 2550);
FORCEPROP 1 LAST BODY_TYPE PLUMBING
J 2
(-1650 2500);
DISPLAY 1.234043 (-1650 2500);
PAINT GREEN (-1650 2500);
DISPLAY INVISIBLE (-1650 2500);
FORCEPROP 1 LAST HDL_TAP TRUE
J 2
(-1975 2425);
DISPLAY 1.234043 (-1975 2425);
PAINT GREEN (-1975 2425);
DISPLAY INVISIBLE (-1975 2425);
FORCEPROP 1 LAST PATH I94
J 2
(-1650 2550);
DISPLAY 0.936170 (-1650 2550);
PAINT GREEN (-1650 2550);
DISPLAY INVISIBLE (-1650 2550);
FORCEADD TAP..6
R 2
(-1650 2350);
FORCEPROP 3 LASTPIN (-1700 2350) SIG_NAME M_C_DQ<13>
J 0
(-1690 2360);
DISPLAY 0.659574 (-1690 2360);
PAINT MONO (-1690 2360);
DISPLAY INVISIBLE (-1690 2360);
FORCEPROP 1 LASTPIN (-1700 2350) BN 13
J 2
(-1650 2360);
DISPLAY 0.617021 (-1650 2360);
PAINT PINK (-1650 2360);
FORCEPROP 2 LAST CDS_LIB mstr_standard
J 2
(-1650 2350);
DISPLAY 0.787234 (-1650 2350);
PAINT MONO (-1650 2350);
DISPLAY INVISIBLE (-1650 2350);
FORCEPROP 1 LAST BODY_TYPE PLUMBING
J 2
(-1650 2300);
DISPLAY 1.234043 (-1650 2300);
PAINT GREEN (-1650 2300);
DISPLAY INVISIBLE (-1650 2300);
FORCEPROP 1 LAST HDL_TAP TRUE
J 2
(-1975 2225);
DISPLAY 1.234043 (-1975 2225);
PAINT GREEN (-1975 2225);
DISPLAY INVISIBLE (-1975 2225);
FORCEPROP 1 LAST PATH I95
J 2
(-1650 2350);
DISPLAY 0.936170 (-1650 2350);
PAINT GREEN (-1650 2350);
DISPLAY INVISIBLE (-1650 2350);
FORCEADD TAP..6
R 2
(-1650 2400);
FORCEPROP 3 LASTPIN (-1700 2400) SIG_NAME M_C_DQ<14>
J 0
(-1690 2410);
DISPLAY 0.659574 (-1690 2410);
PAINT MONO (-1690 2410);
DISPLAY INVISIBLE (-1690 2410);
FORCEPROP 1 LASTPIN (-1700 2400) BN 14
J 2
(-1650 2410);
DISPLAY 0.617021 (-1650 2410);
PAINT PINK (-1650 2410);
FORCEPROP 2 LAST CDS_LIB mstr_standard
J 2
(-1650 2400);
DISPLAY 0.787234 (-1650 2400);
PAINT MONO (-1650 2400);
DISPLAY INVISIBLE (-1650 2400);
FORCEPROP 1 LAST BODY_TYPE PLUMBING
J 2
(-1650 2350);
DISPLAY 1.234043 (-1650 2350);
PAINT GREEN (-1650 2350);
DISPLAY INVISIBLE (-1650 2350);
FORCEPROP 1 LAST HDL_TAP TRUE
J 2
(-1975 2275);
DISPLAY 1.234043 (-1975 2275);
PAINT GREEN (-1975 2275);
DISPLAY INVISIBLE (-1975 2275);
FORCEPROP 1 LAST PATH I96
J 2
(-1650 2400);
DISPLAY 0.936170 (-1650 2400);
PAINT GREEN (-1650 2400);
DISPLAY INVISIBLE (-1650 2400);
FORCEADD TAP..6
R 2
(-1650 2450);
FORCEPROP 3 LASTPIN (-1700 2450) SIG_NAME M_C_DQ<15>
J 0
(-1690 2460);
DISPLAY 0.659574 (-1690 2460);
PAINT MONO (-1690 2460);
DISPLAY INVISIBLE (-1690 2460);
FORCEPROP 1 LASTPIN (-1700 2450) BN 15
J 2
(-1650 2460);
DISPLAY 0.617021 (-1650 2460);
PAINT PINK (-1650 2460);
FORCEPROP 2 LAST CDS_LIB mstr_standard
J 2
(-1650 2450);
DISPLAY 0.787234 (-1650 2450);
PAINT MONO (-1650 2450);
DISPLAY INVISIBLE (-1650 2450);
FORCEPROP 1 LAST BODY_TYPE PLUMBING
J 2
(-1650 2400);
DISPLAY 1.234043 (-1650 2400);
PAINT GREEN (-1650 2400);
DISPLAY INVISIBLE (-1650 2400);
FORCEPROP 1 LAST HDL_TAP TRUE
J 2
(-1975 2325);
DISPLAY 1.234043 (-1975 2325);
PAINT GREEN (-1975 2325);
DISPLAY INVISIBLE (-1975 2325);
FORCEPROP 1 LAST PATH I97
J 2
(-1650 2450);
DISPLAY 0.936170 (-1650 2450);
PAINT GREEN (-1650 2450);
DISPLAY INVISIBLE (-1650 2450);
FORCEADD TAP..6
R 2
(-1650 2250);
FORCEPROP 3 LASTPIN (-1700 2250) SIG_NAME M_C_DQ<11>
J 0
(-1690 2260);
DISPLAY 0.659574 (-1690 2260);
PAINT MONO (-1690 2260);
DISPLAY INVISIBLE (-1690 2260);
FORCEPROP 1 LASTPIN (-1700 2250) BN 11
J 2
(-1650 2260);
DISPLAY 0.617021 (-1650 2260);
PAINT PINK (-1650 2260);
FORCEPROP 2 LAST CDS_LIB mstr_standard
J 2
(-1650 2250);
DISPLAY 0.787234 (-1650 2250);
PAINT MONO (-1650 2250);
DISPLAY INVISIBLE (-1650 2250);
FORCEPROP 1 LAST BODY_TYPE PLUMBING
J 2
(-1650 2200);
DISPLAY 1.234043 (-1650 2200);
PAINT GREEN (-1650 2200);
DISPLAY INVISIBLE (-1650 2200);
FORCEPROP 1 LAST HDL_TAP TRUE
J 2
(-1975 2125);
DISPLAY 1.234043 (-1975 2125);
PAINT GREEN (-1975 2125);
DISPLAY INVISIBLE (-1975 2125);
FORCEPROP 1 LAST PATH I98
J 2
(-1650 2250);
DISPLAY 0.936170 (-1650 2250);
PAINT GREEN (-1650 2250);
DISPLAY INVISIBLE (-1650 2250);
FORCEADD TAP..6
R 2
(-1650 2300);
FORCEPROP 3 LASTPIN (-1700 2300) SIG_NAME M_C_DQ<12>
J 0
(-1690 2310);
DISPLAY 0.659574 (-1690 2310);
PAINT MONO (-1690 2310);
DISPLAY INVISIBLE (-1690 2310);
FORCEPROP 1 LASTPIN (-1700 2300) BN 12
J 2
(-1650 2310);
DISPLAY 0.617021 (-1650 2310);
PAINT PINK (-1650 2310);
FORCEPROP 2 LAST CDS_LIB mstr_standard
J 2
(-1650 2300);
DISPLAY 0.787234 (-1650 2300);
PAINT MONO (-1650 2300);
DISPLAY INVISIBLE (-1650 2300);
FORCEPROP 1 LAST BODY_TYPE PLUMBING
J 2
(-1650 2250);
DISPLAY 1.234043 (-1650 2250);
PAINT GREEN (-1650 2250);
DISPLAY INVISIBLE (-1650 2250);
FORCEPROP 1 LAST HDL_TAP TRUE
J 2
(-1975 2175);
DISPLAY 1.234043 (-1975 2175);
PAINT GREEN (-1975 2175);
DISPLAY INVISIBLE (-1975 2175);
FORCEPROP 1 LAST PATH I99
J 2
(-1650 2300);
DISPLAY 0.936170 (-1650 2300);
PAINT GREEN (-1650 2300);
DISPLAY INVISIBLE (-1650 2300);
FORCEADD BOM_NOTE..1
(-4950 5200);
FORCEPROP 0 LAST L1 UNSTUFF FOR SKU B
J 0
(-5100 5100);
DISPLAY 1.063830 (-5100 5100);
PAINT WHITE (-5100 5100);
FORCEPROP 2 LAST CDS_LIB mstr_symbols
J 0
(-4950 5200);
PAINT ORANGE (-4950 5200);
DISPLAY INVISIBLE (-4950 5200);
FORCEPROP 2 LAST BOM_COST SB
J 0
(-5100 5175);
DISPLAY 1.361702 (-5100 5175);
PAINT ORANGE (-5100 5175);
DISPLAY INVISIBLE (-5100 5175);
FORCEPROP 1 LAST COMMENT_BODY TRUE
J 0
(-4925 5300);
DISPLAY 1.319149 (-4925 5300);
PAINT ORANGE (-4925 5300);
DISPLAY INVISIBLE (-4925 5300);
FORCEPROP 2 LAST ROOM SB_HEADERS
J 0
(-5100 5175);
DISPLAY 1.361702 (-5100 5175);
PAINT ORANGE (-5100 5175);
DISPLAY INVISIBLE (-5100 5175);
FORCEADD INTEL_CORP_BPAGE..1
(2650 500);
FORCEPROP 1 LAST CDS_CON_LAST_MODIFIED Tue Dec 01 11:51:28 2015
J 0
(1225 825);
DISPLAY 0.787234 (1225 825);
PAINT ORANGE (1225 825);
DISPLAY INVISIBLE (1225 825);
FORCEPROP 1 LAST CUSTOM_TXT_CDS <CURRENT_DESIGN_SHEET> OF <TOTAL_DESIGN_SHEETS>
J 0
(2150 525);
PAINT GREEN (2150 525);
FORCEPROP 2 LAST CUSTOM_TXT_CDS <XR_PAGE_TITLE>
J 0
(-5240 5750);
DISPLAY 0.638298 (-5240 5750);
PAINT PINK (-5240 5750);
DISPLAY INVISIBLE (-5240 5750);
FORCEPROP 2 LAST CUSTOM_TXT_CDS <CON_LAST_MODIFIED>
J 0
(1275 825);
DISPLAY 1.042553 (1275 825);
PAINT GREEN (1275 825);
FORCEPROP 1 LAST SCH_ADDRESS3 Santa Clara, CA 95052-8119
J 0
(-1325 525);
DISPLAY 0.617021 (-1325 525);
PAINT GREEN (-1325 525);
FORCEPROP 1 LAST SCH_ADDRESS2 P.O. BOX 58119
J 0
(-1325 575);
DISPLAY 0.617021 (-1325 575);
PAINT GREEN (-1325 575);
FORCEPROP 1 LAST SCH_ADDRESS1 2200 Mission College Blvd.
J 0
(-1325 625);
DISPLAY 0.617021 (-1325 625);
PAINT GREEN (-1325 625);
FORCEPROP 1 LAST SCH_TITLE CPU0 DDR4 CH C DIMM1
J 0
(-5300 550);
DISPLAY 1.212766 (-5300 550);
PAINT WHITE (-5300 550);
FORCEPROP 1 LAST SCH_NUMBER H4694802
J 0
(1350 650);
DISPLAY 1.212766 (1350 650);
PAINT YELLOW (1350 650);
FORCEPROP 1 LAST SCH_DEPT BESD
J 1
(-1800 600);
DISPLAY 1.212766 (-1800 600);
PAINT YELLOW (-1800 600);
FORCEPROP 1 LAST SCH_REV 2.420
J 0
(2400 650);
DISPLAY 0.978723 (2400 650);
PAINT YELLOW (2400 650);
FORCEPROP 2 LAST CDS_LIB mstr_symbols
J 0
(2650 500);
DISPLAY 0.787234 (2650 500);
PAINT MONO (2650 500);
DISPLAY INVISIBLE (2650 500);
FORCEPROP 2 LAST PAGE_BORDER TRUE
J 0
(-5240 5750);
DISPLAY 0.680851 (-5240 5750);
PAINT PINK (-5240 5750);
DISPLAY INVISIBLE (-5240 5750);
FORCEPROP 1 LAST COMMENT_BODY TRUE
J 0
(2660 510);
DISPLAY 0.382979 (2660 510);
PAINT GREEN (2660 510);
DISPLAY INVISIBLE (2660 510);
FORCEPROP 2 LAST CDS_XR_PAGE_TITLE CR-48 : @BASEBOARD_FAB2_LIB.BASEBOARD_FAB2(SCH_1):PAGE48
J 0
(-5240 5750);
DISPLAY 0.638298 (-5240 5750);
PAINT PINK (-5240 5750);
DISPLAY INVISIBLE (-5240 5750);
WIRE 17 -1 (750 5075)(750 5175);
WIRE 17 -1 (750 4975)(750 5075);
WIRE 17 -1 (750 5175)(750 5200);
WIRE 17 -1 (1550 5200)(750 5200);
FORCEPROP 2 LAST SIG_NAME M_C_DQS_DP<17:0>
J 0
(1000 5210);
DISPLAY 0.617021 (1000 5210);
PAINT ORANGE (1000 5210);
WIRE 17 -1 (750 4375)(750 4475);
WIRE 17 -1 (750 4275)(750 4375);
WIRE 17 -1 (750 4475)(750 4575);
WIRE 17 -1 (750 4575)(750 4675);
WIRE 17 -1 (750 4175)(750 4275);
WIRE 17 -1 (750 4075)(750 4175);
WIRE 17 -1 (750 4675)(750 4775);
WIRE 17 -1 (750 4775)(750 4875);
WIRE 17 -1 (750 3975)(750 4075);
WIRE 17 -1 (750 3875)(750 3975);
WIRE 17 -1 (750 4875)(750 4975);
WIRE 17 -1 (750 3775)(750 3875);
WIRE 17 -1 (750 3675)(750 3775);
WIRE 17 -1 (750 3575)(750 3675);
WIRE 17 -1 (750 3475)(750 3575);
WIRE 17 -1 (950 4225)(950 4325);
WIRE 17 -1 (950 4125)(950 4225);
WIRE 17 -1 (950 4325)(950 4425);
WIRE 17 -1 (950 4425)(950 4525);
WIRE 17 -1 (950 4025)(950 4125);
WIRE 17 -1 (950 3925)(950 4025);
WIRE 17 -1 (950 4525)(950 4625);
WIRE 17 -1 (950 4625)(950 4725);
WIRE 17 -1 (950 3825)(950 3925);
WIRE 17 -1 (950 3725)(950 3825);
WIRE 17 -1 (950 4725)(950 4825);
WIRE 17 -1 (950 4825)(950 4925);
WIRE 17 -1 (950 3625)(950 3725);
WIRE 17 -1 (950 3525)(950 3625);
WIRE 17 -1 (950 4925)(950 5025);
WIRE 17 -1 (950 5025)(950 5125);
WIRE 17 -1 (950 3425)(950 3525);
WIRE 17 -1 (950 5125)(950 5150);
WIRE 17 -1 (1550 5150)(950 5150);
FORCEPROP 2 LAST SIG_NAME M_C_DQS_DN<17:0>
J 0
(1000 5160);
DISPLAY 0.617021 (1000 5160);
PAINT ORANGE (1000 5160);
WIRE 17 -1 (-1600 4625)(-1600 4675);
WIRE 17 -1 (-1600 4575)(-1600 4625);
WIRE 17 -1 (-1600 4675)(-1600 4725);
WIRE 17 -1 (-1600 4725)(-1600 4775);
WIRE 17 -1 (-1600 4525)(-1600 4575);
WIRE 17 -1 (-1600 4475)(-1600 4525);
WIRE 17 -1 (-1600 4775)(-1600 4825);
WIRE 17 -1 (-1600 4825)(-1600 4875);
WIRE 17 -1 (-1600 4425)(-1600 4475);
WIRE 17 -1 (-1600 4375)(-1600 4425);
WIRE 17 -1 (-1600 4875)(-1600 4900);
WIRE 17 -1 (-1150 4900)(-1600 4900);
FORCEPROP 2 LAST SIG_NAME M_C_DQ<63:0>
J 0
(-1560 4910);
DISPLAY 0.617021 (-1560 4910);
PAINT ORANGE (-1560 4910);
WIRE 17 -1 (-1600 4125)(-1600 4175);
WIRE 17 -1 (-1600 4075)(-1600 4125);
WIRE 17 -1 (-1600 4175)(-1600 4225);
WIRE 17 -1 (-1600 4225)(-1600 4275);
WIRE 17 -1 (-1600 4025)(-1600 4075);
WIRE 17 -1 (-1600 3975)(-1600 4025);
WIRE 17 -1 (-1600 4275)(-1600 4325);
WIRE 17 -1 (-1600 4325)(-1600 4375);
WIRE 17 -1 (-1600 3925)(-1600 3975);
WIRE 17 -1 (-1600 3875)(-1600 3925);
WIRE 17 -1 (-1600 3825)(-1600 3875);
WIRE 17 -1 (-1600 3775)(-1600 3825);
WIRE 17 -1 (-1600 3725)(-1600 3775);
WIRE 17 -1 (-1600 3675)(-1600 3725);
WIRE 17 -1 (-1600 3625)(-1600 3675);
WIRE 17 -1 (-1600 3575)(-1600 3625);
WIRE 17 -1 (-1600 3525)(-1600 3575);
WIRE 17 -1 (-1600 3475)(-1600 3525);
WIRE 17 -1 (-1600 3425)(-1600 3475);
WIRE 17 -1 (-1600 3375)(-1600 3425);
WIRE 17 -1 (-3200 4775)(-3200 4825);
WIRE 17 -1 (-3200 4725)(-3200 4775);
WIRE 17 -1 (-3200 4825)(-3200 4875);
WIRE 17 -1 (-3200 4875)(-3200 4900);
WIRE 17 -1 (-3200 4675)(-3200 4725);
WIRE 17 -1 (-3200 4625)(-3200 4675);
WIRE 17 -1 (-3700 4900)(-3200 4900);
FORCEPROP 2 LAST SIG_NAME M_C_MA<17:0>
J 0
(-3650 4910);
DISPLAY 0.617021 (-3650 4910);
PAINT ORANGE (-3650 4910);
WIRE 17 -1 (-3200 4575)(-3200 4625);
WIRE 17 -1 (-3200 4525)(-3200 4575);
WIRE 17 -1 (-3200 4475)(-3200 4525);
WIRE 17 -1 (-3200 4425)(-3200 4475);
WIRE 17 -1 (-3200 4375)(-3200 4425);
WIRE 17 -1 (-3200 4325)(-3200 4375);
WIRE 17 -1 (-3200 4275)(-3200 4325);
WIRE 17 -1 (-3200 4225)(-3200 4275);
WIRE 17 -1 (-3200 4175)(-3200 4225);
WIRE 17 -1 (-3200 4125)(-3200 4175);
WIRE 17 -1 (-3200 4075)(-3200 4125);
WIRE 17 -1 (-3200 4025)(-3200 4075);
WIRE 17 -1 (-1600 3325)(-1600 3375);
WIRE 17 -1 (-1600 3275)(-1600 3325);
WIRE 17 -1 (-1600 3225)(-1600 3275);
WIRE 17 -1 (-1600 3175)(-1600 3225);
WIRE 17 -1 (-1600 3125)(-1600 3175);
WIRE 17 -1 (-1600 3075)(-1600 3125);
WIRE 17 -1 (-1600 3025)(-1600 3075);
WIRE 17 -1 (-1600 2975)(-1600 3025);
WIRE 17 -1 (-1600 2925)(-1600 2975);
WIRE 17 -1 (-1600 2875)(-1600 2925);
WIRE 17 -1 (-1600 2825)(-1600 2875);
WIRE 17 -1 (-1600 2775)(-1600 2825);
WIRE 17 -1 (-1600 2725)(-1600 2775);
WIRE 17 -1 (-1600 2675)(-1600 2725);
WIRE 17 -1 (-1600 2625)(-1600 2675);
WIRE 17 -1 (-1600 2575)(-1600 2625);
WIRE 17 -1 (-1600 2525)(-1600 2575);
WIRE 17 -1 (-1600 2475)(-1600 2525);
WIRE 17 -1 (-1600 2425)(-1600 2475);
WIRE 17 -1 (-1600 2375)(-1600 2425);
WIRE 17 -1 (-1600 2325)(-1600 2375);
WIRE 17 -1 (-1600 2275)(-1600 2325);
WIRE 17 -1 (-1600 2225)(-1600 2275);
WIRE 17 -1 (-1600 2175)(-1600 2225);
WIRE 17 -1 (-1600 2125)(-1600 2175);
WIRE 17 -1 (-1600 2075)(-1600 2125);
WIRE 17 -1 (-1600 2025)(-1600 2075);
WIRE 17 -1 (-1600 1975)(-1600 2025);
WIRE 17 -1 (-1600 1925)(-1600 1975);
WIRE 17 -1 (-1600 1875)(-1600 1925);
WIRE 17 -1 (-1600 1825)(-1600 1875);
WIRE 17 -1 (-1600 1775)(-1600 1825);
WIRE 17 -1 (-1600 1725)(-1600 1775);
WIRE 17 -1 (-3400 3625)(-3400 3525);
WIRE 17 -1 (-3400 3650)(-3400 3625);
WIRE 17 -1 (-3400 3650)(-3900 3650);
FORCEPROP 2 LAST SIG_NAME M_C_CLK_DN<3:0>
J 0
(-3850 3660);
DISPLAY 0.617021 (-3850 3660);
PAINT ORANGE (-3850 3660);
WIRE 17 -1 (-3200 3325)(-3200 3375);
WIRE 17 -1 (-3200 3275)(-3200 3325);
WIRE 17 -1 (-3200 3400)(-3200 3375);
WIRE 17 -1 (-3200 3400)(-3700 3400);
FORCEPROP 2 LAST SIG_NAME M_C_CS_N<7:0>
J 0
(-3650 3410);
DISPLAY 0.617021 (-3650 3410);
PAINT ORANGE (-3650 3410);
WIRE 17 -1 (-3200 3075)(-3200 3125);
WIRE 17 -1 (-3200 3150)(-3200 3125);
WIRE 17 -1 (-3200 3150)(-3700 3150);
FORCEPROP 2 LAST SIG_NAME M_C_CKE<3:0>
J 0
(-3650 3160);
DISPLAY 0.617021 (-3650 3160);
PAINT ORANGE (-3650 3160);
WIRE 17 -1 (-3200 2925)(-3200 2975);
WIRE 17 -1 (-3200 3000)(-3200 2975);
WIRE 17 -1 (-3200 3000)(-3700 3000);
FORCEPROP 2 LAST SIG_NAME M_C_ODT<3:0>
J 0
(-3650 3010);
DISPLAY 0.617021 (-3650 3010);
PAINT ORANGE (-3650 3010);
WIRE 17 -1 (-3200 3225)(-3200 3275);
WIRE 17 -1 (-3200 2775)(-3200 2825);
WIRE 17 -1 (-3200 2725)(-3200 2775);
WIRE 17 -1 (-3200 2850)(-3200 2825);
WIRE 17 -1 (-3200 2850)(-3700 2850);
FORCEPROP 2 LAST SIG_NAME M_C_ECC<7:0>
J 0
(-3650 2860);
DISPLAY 0.617021 (-3650 2860);
PAINT ORANGE (-3650 2860);
WIRE 17 -1 (-3200 3875)(-3200 3925);
WIRE 17 -1 (-3200 3950)(-3200 3925);
WIRE 17 -1 (-3200 3950)(-3700 3950);
FORCEPROP 2 LAST SIG_NAME M_C_BA<1:0>
J 0
(-3650 3960);
DISPLAY 0.617021 (-3650 3960);
PAINT ORANGE (-3650 3960);
WIRE 17 -1 (-3200 3775)(-3200 3825);
WIRE 17 -1 (-3200 3850)(-3200 3825);
WIRE 17 -1 (-3200 3850)(-3700 3850);
FORCEPROP 2 LAST SIG_NAME M_C_BG<1:0>
J 0
(-3650 3860);
DISPLAY 0.617021 (-3650 3860);
PAINT ORANGE (-3650 3860);
WIRE 17 -1 (-3200 3575)(-3200 3675);
WIRE 17 -1 (-3200 3700)(-3200 3675);
WIRE 17 -1 (-3200 3700)(-3900 3700);
FORCEPROP 2 LAST SIG_NAME M_C_CLK_DP<3:0>
J 0
(-3850 3710);
DISPLAY 0.617021 (-3850 3710);
PAINT ORANGE (-3850 3710);
WIRE 17 -1 (-3200 2475)(-3200 2525);
WIRE 17 -1 (-3200 2525)(-3200 2575);
WIRE 17 -1 (-3200 2575)(-3200 2625);
WIRE 17 -1 (-3200 2625)(-3200 2675);
WIRE 17 -1 (-3200 2675)(-3200 2725);
WIRE 16 -1 (-800 2500)(-600 2500);
WIRE 16 -1 (-800 2500)(-800 2550);
WIRE 16 -1 (-800 2550)(-600 2550);
WIRE 16 -1 (-950 2550)(-800 2550);
WIRE 16 -1 (-950 2650)(-950 2550);
WIRE 16 -1 (-800 1150)(-600 1150);
WIRE 16 -1 (-800 1150)(-800 1200);
WIRE 16 -1 (-800 1200)(-600 1200);
WIRE 16 -1 (-800 1200)(-800 1250);
WIRE 16 -1 (-800 1250)(-600 1250);
WIRE 16 -1 (-800 1250)(-800 1300);
WIRE 16 -1 (-800 1300)(-600 1300);
WIRE 16 -1 (-800 1300)(-800 1350);
WIRE 16 -1 (-800 1350)(-600 1350);
WIRE 16 -1 (-800 1350)(-800 1400);
WIRE 16 -1 (-800 1400)(-600 1400);
WIRE 16 -1 (-800 1400)(-800 1450);
WIRE 16 -1 (-800 1450)(-600 1450);
WIRE 16 -1 (-800 1450)(-800 1500);
WIRE 16 -1 (-800 1500)(-800 1550);
WIRE 16 -1 (-800 1500)(-600 1500);
WIRE 16 -1 (-800 1550)(-600 1550);
WIRE 16 -1 (-800 1550)(-800 1600);
WIRE 16 -1 (-800 1600)(-600 1600);
WIRE 16 -1 (-800 1600)(-800 1650);
WIRE 16 -1 (-800 1650)(-600 1650);
WIRE 16 -1 (-800 1650)(-800 1700);
WIRE 16 -1 (-800 1700)(-600 1700);
WIRE 16 -1 (-800 1700)(-800 1750);
WIRE 16 -1 (-800 1750)(-600 1750);
WIRE 16 -1 (-800 1750)(-800 1800);
WIRE 16 -1 (-800 1800)(-600 1800);
WIRE 16 -1 (-800 1800)(-800 1850);
WIRE 16 -1 (-800 1850)(-600 1850);
WIRE 16 -1 (-800 1850)(-800 1900);
WIRE 16 -1 (-800 1900)(-600 1900);
WIRE 16 -1 (-800 1900)(-800 1950);
WIRE 16 -1 (-800 1950)(-600 1950);
WIRE 16 -1 (-800 1950)(-800 2000);
WIRE 16 -1 (-800 2000)(-800 2050);
WIRE 16 -1 (-800 2000)(-600 2000);
WIRE 16 -1 (-800 2050)(-600 2050);
WIRE 16 -1 (-800 2050)(-800 2100);
WIRE 16 -1 (-800 2100)(-600 2100);
WIRE 16 -1 (-800 2100)(-800 2150);
WIRE 16 -1 (-800 2150)(-600 2150);
WIRE 16 -1 (-800 2150)(-800 2200);
WIRE 16 -1 (-800 2200)(-600 2200);
WIRE 16 -1 (-800 2200)(-800 2250);
WIRE 16 -1 (-800 2250)(-600 2250);
WIRE 16 -1 (-800 2250)(-800 2300);
WIRE 16 -1 (-800 2300)(-600 2300);
WIRE 16 -1 (-800 2300)(-800 2350);
WIRE 16 -1 (-800 2350)(-600 2350);
WIRE 16 -1 (-800 2350)(-800 2400);
WIRE 16 -1 (-800 2400)(-600 2400);
WIRE 16 -1 (-1150 2400)(-800 2400);
WIRE 16 -1 (-1150 2500)(-1150 2400);
WIRE 16 -1 (2500 3700)(2500 3750);
WIRE 16 -1 (2500 3650)(2500 3700);
WIRE 16 -1 (2500 3700)(2300 3700);
WIRE 16 -1 (2500 3750)(2300 3750);
WIRE 16 -1 (2500 3600)(2500 3650);
WIRE 16 -1 (2500 3650)(2300 3650);
WIRE 16 -1 (2500 3600)(2300 3600);
WIRE 16 -1 (2500 3550)(2500 3600);
WIRE 16 -1 (2500 3500)(2500 3550);
WIRE 16 -1 (2500 3550)(2300 3550);
WIRE 16 -1 (2500 3450)(2500 3500);
WIRE 16 -1 (2500 3500)(2300 3500);
WIRE 16 -1 (2500 3400)(2500 3450);
WIRE 16 -1 (2500 3450)(2300 3450);
WIRE 16 -1 (2500 3350)(2500 3400);
WIRE 16 -1 (2500 3400)(2300 3400);
WIRE 16 -1 (2500 3300)(2500 3350);
WIRE 16 -1 (2500 3350)(2300 3350);
WIRE 16 -1 (2500 3250)(2500 3300);
WIRE 16 -1 (2500 3300)(2300 3300);
WIRE 16 -1 (2500 3200)(2500 3250);
WIRE 16 -1 (2500 3250)(2300 3250);
WIRE 16 -1 (2500 3150)(2500 3200);
WIRE 16 -1 (2500 3200)(2300 3200);
WIRE 16 -1 (2500 3100)(2500 3150);
WIRE 16 -1 (2500 3150)(2300 3150);
WIRE 16 -1 (2500 3100)(2300 3100);
WIRE 16 -1 (2500 3050)(2500 3100);
WIRE 16 -1 (2500 3000)(2500 3050);
WIRE 16 -1 (2500 3050)(2300 3050);
WIRE 16 -1 (2500 2950)(2500 3000);
WIRE 16 -1 (2500 3000)(2300 3000);
WIRE 16 -1 (2500 2900)(2500 2950);
WIRE 16 -1 (2500 2950)(2300 2950);
WIRE 16 -1 (2500 2850)(2500 2900);
WIRE 16 -1 (2500 2900)(2300 2900);
WIRE 16 -1 (2500 2800)(2500 2850);
WIRE 16 -1 (2500 2850)(2300 2850);
WIRE 16 -1 (2500 2750)(2500 2800);
WIRE 16 -1 (2500 2800)(2300 2800);
WIRE 16 -1 (2500 2700)(2500 2750);
WIRE 16 -1 (2500 2750)(2300 2750);
WIRE 16 -1 (2500 2650)(2500 2700);
WIRE 16 -1 (2500 2700)(2300 2700);
WIRE 16 -1 (2500 2600)(2500 2650);
WIRE 16 -1 (2500 2650)(2300 2650);
WIRE 16 -1 (2500 2600)(2300 2600);
WIRE 16 -1 (2500 2550)(2500 2600);
WIRE 16 -1 (2500 2500)(2500 2550);
WIRE 16 -1 (2500 2550)(2300 2550);
WIRE 16 -1 (2500 2450)(2500 2500);
WIRE 16 -1 (2500 2500)(2300 2500);
WIRE 16 -1 (2500 2400)(2500 2450);
WIRE 16 -1 (2500 2450)(2300 2450);
WIRE 16 -1 (2500 2350)(2500 2400);
WIRE 16 -1 (2500 2400)(2300 2400);
WIRE 16 -1 (2500 2300)(2500 2350);
WIRE 16 -1 (2500 2350)(2300 2350);
WIRE 16 -1 (2500 2250)(2500 2300);
WIRE 16 -1 (2500 2300)(2300 2300);
WIRE 16 -1 (2500 2200)(2500 2250);
WIRE 16 -1 (2500 2250)(2300 2250);
WIRE 16 -1 (2500 2150)(2500 2200);
WIRE 16 -1 (2500 2200)(2300 2200);
WIRE 16 -1 (2500 2100)(2500 2150);
WIRE 16 -1 (2500 2150)(2300 2150);
WIRE 16 -1 (2500 2050)(2500 2100);
WIRE 16 -1 (2500 2100)(2300 2100);
WIRE 16 -1 (2500 2050)(2300 2050);
WIRE 16 -1 (2500 2000)(2500 2050);
WIRE 16 -1 (2500 1950)(2500 2000);
WIRE 16 -1 (2500 2000)(2300 2000);
WIRE 16 -1 (2500 1900)(2500 1950);
WIRE 16 -1 (2500 1950)(2300 1950);
WIRE 16 -1 (2500 1850)(2500 1900);
WIRE 16 -1 (2500 1900)(2300 1900);
WIRE 16 -1 (2500 1800)(2500 1850);
WIRE 16 -1 (2500 1850)(2300 1850);
WIRE 16 -1 (2500 1750)(2500 1800);
WIRE 16 -1 (2500 1800)(2300 1800);
WIRE 16 -1 (2500 1700)(2500 1750);
WIRE 16 -1 (2500 1750)(2300 1750);
WIRE 16 -1 (2500 1650)(2500 1700);
WIRE 16 -1 (2500 1700)(2300 1700);
WIRE 16 -1 (2500 1600)(2500 1650);
WIRE 16 -1 (2500 1650)(2300 1650);
WIRE 16 -1 (2500 1550)(2500 1600);
WIRE 16 -1 (2500 1600)(2300 1600);
WIRE 16 -1 (2500 1550)(2300 1550);
WIRE 16 -1 (2500 1500)(2500 1550);
WIRE 16 -1 (2500 1450)(2500 1500);
WIRE 16 -1 (2500 1500)(2300 1500);
WIRE 16 -1 (2500 1350)(2500 1450);
WIRE 16 -1 (2500 1450)(2300 1450);
WIRE 16 -1 (-4650 1400)(-4650 1300);
WIRE 16 -1 (-800 2650)(-600 2650);
WIRE 16 -1 (-800 2650)(-800 2700);
WIRE 16 -1 (-800 2700)(-600 2700);
WIRE 16 -1 (-800 2700)(-800 2750);
WIRE 16 -1 (-600 2750)(-800 2750);
WIRE 16 -1 (-800 2800)(-800 2750);
WIRE 16 -1 (-800 2800)(-600 2800);
WIRE 16 -1 (-800 2800)(-800 2850);
WIRE 16 -1 (-800 2850)(-600 2850);
WIRE 16 -1 (-800 2950)(-800 2850);
WIRE 16 -1 (-2900 1900)(-3100 1900);
WIRE 16 -1 (-3100 1900)(-3100 2000);
WIRE 16 -1 (-2900 2000)(-3100 2000);
WIRE 16 -1 (-3100 2000)(-3100 2050);
WIRE 16 -1 (-2900 2050)(-3100 2050);
WIRE 16 -1 (-3100 2050)(-4650 2050);
WIRE 16 -1 (-4650 2200)(-4650 2050);
WIRE 16 -1 (-2900 1950)(-4650 1950);
WIRE 16 -1 (-4650 1950)(-4650 1900);
WIRE 16 -1 (400 2800)(600 2800);
WIRE 16 -1 (600 2800)(600 2850);
WIRE 16 -1 (400 2850)(600 2850);
WIRE 16 -1 (600 2850)(600 3025);
WIRE 16 -1 (1100 3750)(1300 3750);
WIRE 16 -1 (1100 3700)(1100 3750);
WIRE 16 -1 (1100 3700)(1300 3700);
WIRE 16 -1 (1100 3650)(1100 3700);
WIRE 16 -1 (1100 3650)(1300 3650);
WIRE 16 -1 (1100 3600)(1100 3650);
WIRE 16 -1 (1100 3600)(1300 3600);
WIRE 16 -1 (1100 3550)(1100 3600);
WIRE 16 -1 (1100 3550)(1300 3550);
WIRE 16 -1 (1100 3500)(1100 3550);
WIRE 16 -1 (1100 3500)(1300 3500);
WIRE 16 -1 (1100 3450)(1100 3500);
WIRE 16 -1 (1100 3450)(1300 3450);
WIRE 16 -1 (1100 3400)(1100 3450);
WIRE 16 -1 (1100 3400)(1300 3400);
WIRE 16 -1 (1100 3350)(1100 3400);
WIRE 16 -1 (1100 3350)(1300 3350);
WIRE 16 -1 (1100 3300)(1100 3350);
WIRE 16 -1 (1100 3300)(1300 3300);
WIRE 16 -1 (1100 3250)(1100 3300);
WIRE 16 -1 (1100 3250)(1300 3250);
WIRE 16 -1 (1100 3200)(1100 3250);
WIRE 16 -1 (1100 3200)(1300 3200);
WIRE 16 -1 (1100 3150)(1100 3200);
WIRE 16 -1 (1100 3150)(1300 3150);
WIRE 16 -1 (1100 3100)(1100 3150);
WIRE 16 -1 (1100 3100)(1300 3100);
WIRE 16 -1 (1100 3050)(1100 3100);
WIRE 16 -1 (1100 3050)(1300 3050);
WIRE 16 -1 (1100 3000)(1100 3050);
WIRE 16 -1 (1100 3000)(1300 3000);
WIRE 16 -1 (1100 2950)(1100 3000);
WIRE 16 -1 (1100 2950)(1300 2950);
WIRE 16 -1 (1100 2900)(1100 2950);
WIRE 16 -1 (1100 2900)(1300 2900);
WIRE 16 -1 (1100 2850)(1100 2900);
WIRE 16 -1 (1100 2850)(1300 2850);
WIRE 16 -1 (1100 2800)(1100 2850);
WIRE 16 -1 (1100 2800)(1300 2800);
WIRE 16 -1 (1100 2750)(1100 2800);
WIRE 16 -1 (1100 2750)(1300 2750);
WIRE 16 -1 (1100 2700)(1100 2750);
WIRE 16 -1 (1100 2700)(1300 2700);
WIRE 16 -1 (1100 2650)(1100 2700);
WIRE 16 -1 (1100 2650)(1300 2650);
WIRE 16 -1 (1100 2600)(1100 2650);
WIRE 16 -1 (1100 2600)(1300 2600);
WIRE 16 -1 (1100 2550)(1100 2600);
WIRE 16 -1 (1100 2550)(1300 2550);
WIRE 16 -1 (1100 2500)(1100 2550);
WIRE 16 -1 (1100 2500)(1300 2500);
WIRE 16 -1 (1100 2450)(1100 2500);
WIRE 16 -1 (1100 2450)(1300 2450);
WIRE 16 -1 (1100 2400)(1100 2450);
WIRE 16 -1 (1100 2400)(1300 2400);
WIRE 16 -1 (1100 2350)(1100 2400);
WIRE 16 -1 (1100 2350)(1300 2350);
WIRE 16 -1 (1100 2300)(1100 2350);
WIRE 16 -1 (1100 2300)(1300 2300);
WIRE 16 -1 (1100 2250)(1100 2300);
WIRE 16 -1 (1100 2250)(1300 2250);
WIRE 16 -1 (1100 2200)(1100 2250);
WIRE 16 -1 (1100 2200)(1300 2200);
WIRE 16 -1 (1100 2150)(1100 2200);
WIRE 16 -1 (1100 2150)(1300 2150);
WIRE 16 -1 (1100 2100)(1100 2150);
WIRE 16 -1 (1100 2100)(1300 2100);
WIRE 16 -1 (1100 2050)(1100 2100);
WIRE 16 -1 (1100 2050)(1300 2050);
WIRE 16 -1 (1100 2000)(1100 2050);
WIRE 16 -1 (1100 2000)(1300 2000);
WIRE 16 -1 (1100 1950)(1100 2000);
WIRE 16 -1 (1100 1950)(1300 1950);
WIRE 16 -1 (1100 1900)(1100 1950);
WIRE 16 -1 (1100 1900)(1300 1900);
WIRE 16 -1 (1100 1850)(1100 1900);
WIRE 16 -1 (1100 1850)(1300 1850);
WIRE 16 -1 (1100 1800)(1100 1850);
WIRE 16 -1 (1100 1800)(1300 1800);
WIRE 16 -1 (1100 1750)(1100 1800);
WIRE 16 -1 (1100 1750)(1300 1750);
WIRE 16 -1 (1100 1700)(1100 1750);
WIRE 16 -1 (1100 1700)(1300 1700);
WIRE 16 -1 (1100 1650)(1100 1700);
WIRE 16 -1 (1100 1650)(1300 1650);
WIRE 16 -1 (1100 1600)(1100 1650);
WIRE 16 -1 (1100 1600)(1300 1600);
WIRE 16 -1 (1100 1550)(1100 1600);
WIRE 16 -1 (1100 1550)(1300 1550);
WIRE 16 -1 (1100 1500)(1100 1550);
WIRE 16 -1 (1100 1500)(1300 1500);
WIRE 16 -1 (1100 1450)(1100 1500);
WIRE 16 -1 (1100 1450)(1300 1450);
WIRE 16 -1 (1100 1350)(1100 1450);
WIRE 16 -1 (-2900 1700)(-4650 1700);
FORCEPROP 2 LAST SIG_NAME M_C_VREF
J 0
(-3675 1710);
DISPLAY 0.617021 (-3675 1710);
PAINT ORANGE (-3675 1710);
WIRE 16 -1 (-4650 1700)(-4650 1600);
WIRE 16 -1 (-4750 1700)(-4650 1700);
WIRE 16 -1 (-3750 1600)(-2900 1600);
FORCEPROP 2 LAST SIG_NAME TP_CH_C_DIMM_C1_RFU_2
J 0
(-3700 1610);
DISPLAY 0.617021 (-3700 1610);
PAINT ORANGE (-3700 1610);
FORCEPROP 2 LASTPROP $XRERR UNIQUE?
J 0
(-3990 1600);
DISPLAY 0.638298 (-3990 1600);
PAINT MONO (-3990 1600);
DISPLAY INVISIBLE (-3990 1600);
WIRE 16 -1 (-3750 1500)(-2900 1500);
FORCEPROP 2 LAST SIG_NAME TP_CH_C_DIMM_C1_RFU_0
J 0
(-3700 1510);
DISPLAY 0.617021 (-3700 1510);
PAINT ORANGE (-3700 1510);
FORCEPROP 2 LASTPROP $XRERR UNIQUE?
J 0
(-3990 1500);
DISPLAY 0.638298 (-3990 1500);
PAINT MONO (-3990 1500);
DISPLAY INVISIBLE (-3990 1500);
WIRE 16 -1 (-3750 1550)(-2900 1550);
FORCEPROP 2 LAST SIG_NAME TP_CH_C_DIMM_C1_RFU_1
J 0
(-3700 1560);
DISPLAY 0.617021 (-3700 1560);
PAINT ORANGE (-3700 1560);
FORCEPROP 2 LASTPROP $XRERR UNIQUE?
J 0
(-3990 1550);
DISPLAY 0.638298 (-3990 1550);
PAINT MONO (-3990 1550);
DISPLAY INVISIBLE (-3990 1550);
WIRE 16 -1 (-3700 1800)(-2900 1800);
FORCEPROP 2 LAST SIG_NAME SMB_DDR_ABC_VPP_SCL
J 0
(-3660 1810);
DISPLAY 0.617021 (-3660 1810);
PAINT ORANGE (-3660 1810);
WIRE 16 -1 (-3700 1850)(-2900 1850);
FORCEPROP 2 LAST SIG_NAME SMB_DDR_ABC_VPP_SDA
J 0
(-3660 1860);
DISPLAY 0.617021 (-3660 1860);
PAINT ORANGE (-3660 1860);
WIRE 16 -1 (-3750 1400)(-2900 1400);
FORCEPROP 2 LAST SIG_NAME FM_ADR_COMPLETE_ABC_N
J 0
(-3700 1410);
DISPLAY 0.617021 (-3700 1410);
PAINT ORANGE (-3700 1410);
WIRE 16 -1 (-3350 2250)(-2900 2250);
WIRE 16 -1 (-3350 2250)(-3350 2500);
WIRE 16 -1 (-3350 2500)(-4075 2500);
FORCEPROP 2 LAST SIG_NAME FM_DIMM_EVENT_COD_N
J 0
(-4056 2497);
DISPLAY 0.617021 (-4056 2497);
PAINT ORANGE (-4056 2497);
WIRE 16 -1 (-3250 2350)(-2900 2350);
WIRE 16 -1 (-3250 2350)(-3250 2800);
WIRE 16 -1 (-3250 2800)(-3700 2800);
FORCEPROP 2 LAST SIG_NAME M_C_PAR
J 0
(-3650 2810);
DISPLAY 0.617021 (-3650 2810);
PAINT ORANGE (-3650 2810);
WIRE 16 -1 (-3300 2300)(-2900 2300);
WIRE 16 -1 (-3300 2300)(-3300 2750);
WIRE 16 -1 (-3300 2750)(-3700 2750);
FORCEPROP 2 LAST SIG_NAME M_ABC_RST_N
J 0
(-3650 2760);
DISPLAY 0.617021 (-3650 2760);
PAINT ORANGE (-3650 2760);
WIRE 16 -1 (-2900 3900)(-3100 3900);
WIRE 16 -1 (-2900 3600)(-3300 3600);
WIRE 16 -1 (-2900 3550)(-3100 3550);
WIRE 16 -1 (-2900 3300)(-3100 3300);
WIRE 16 -1 (-2900 3250)(-3100 3250);
WIRE 16 -1 (-2900 4000)(-3100 4000);
WIRE 16 -1 (-2900 4050)(-3100 4050);
WIRE 16 -1 (-2900 2750)(-3100 2750);
WIRE 16 -1 (-2900 2700)(-3100 2700);
WIRE 16 -1 (-2900 2650)(-3100 2650);
WIRE 16 -1 (-2900 2600)(-3100 2600);
WIRE 16 -1 (-2900 2550)(-3100 2550);
WIRE 16 -1 (-2900 2500)(-3100 2500);
WIRE 16 -1 (-2900 2450)(-3100 2450);
WIRE 16 -1 (-2900 3100)(-3100 3100);
WIRE 16 -1 (-2900 3650)(-3100 3650);
WIRE 16 -1 (-2900 3750)(-3100 3750);
WIRE 16 -1 (-2900 3800)(-3100 3800);
WIRE 16 -1 (-2900 3850)(-3100 3850);
WIRE 16 -1 (-2900 2800)(-3100 2800);
WIRE 16 -1 (-2900 2900)(-3100 2900);
WIRE 16 -1 (-2900 3200)(-3100 3200);
WIRE 16 -1 (-2900 2950)(-3100 2950);
WIRE 16 -1 (-2900 3050)(-3100 3050);
WIRE 16 -1 (-2900 3350)(-3100 3350);
WIRE 16 -1 (-2900 3500)(-3300 3500);
WIRE 16 -1 (-3925 2200)(-2900 2200);
FORCEPROP 2 LAST SIG_NAME M_C_ALERT_N
J 0
(-3900 2210);
DISPLAY 0.617021 (-3900 2210);
PAINT ORANGE (-3900 2210);
WIRE 16 -1 (-3900 2150)(-2900 2150);
FORCEPROP 2 LAST SIG_NAME M_C_ACT_N
J 0
(-3875 2160);
DISPLAY 0.617021 (-3875 2160);
PAINT ORANGE (-3875 2160);
WIRE 16 -1 (-3050 3400)(-2900 3400);
WIRE 16 -1 (-3050 3400)(-3050 3450);
WIRE 16 -1 (-3050 3450)(-3700 3450);
FORCEPROP 2 LAST SIG_NAME M_C_C<2>
J 0
(-3650 3460);
DISPLAY 0.617021 (-3650 3460);
PAINT ORANGE (-3650 3460);
WIRE 16 -1 (-1700 2000)(-1900 2000);
WIRE 16 -1 (-1700 1750)(-1900 1750);
WIRE 16 -1 (-1700 1700)(-1900 1700);
WIRE 16 -1 (-1700 1800)(-1900 1800);
WIRE 16 -1 (-1700 1850)(-1900 1850);
WIRE 16 -1 (-1700 1900)(-1900 1900);
WIRE 16 -1 (-1700 1950)(-1900 1950);
WIRE 16 -1 (-1700 2500)(-1900 2500);
WIRE 16 -1 (-1700 2400)(-1900 2400);
WIRE 16 -1 (-1700 2350)(-1900 2350);
WIRE 16 -1 (-1700 2300)(-1900 2300);
WIRE 16 -1 (-1700 2200)(-1900 2200);
WIRE 16 -1 (-1700 2150)(-1900 2150);
WIRE 16 -1 (-1700 2100)(-1900 2100);
WIRE 16 -1 (-1700 2050)(-1900 2050);
WIRE 16 -1 (-1700 2450)(-1900 2450);
WIRE 16 -1 (-1700 2550)(-1900 2550);
WIRE 16 -1 (-1700 2250)(-1900 2250);
WIRE 16 -1 (-1700 2950)(-1900 2950);
WIRE 16 -1 (-1700 2900)(-1900 2900);
WIRE 16 -1 (-1700 2850)(-1900 2850);
WIRE 16 -1 (-1700 2800)(-1900 2800);
WIRE 16 -1 (-1700 2750)(-1900 2750);
WIRE 16 -1 (-1700 2650)(-1900 2650);
WIRE 16 -1 (-1700 2600)(-1900 2600);
WIRE 16 -1 (-1700 3050)(-1900 3050);
WIRE 16 -1 (-1700 3000)(-1900 3000);
WIRE 16 -1 (-1700 2700)(-1900 2700);
WIRE 16 -1 (-1700 3150)(-1900 3150);
WIRE 16 -1 (-1700 3100)(-1900 3100);
WIRE 16 -1 (-1700 3550)(-1900 3550);
WIRE 16 -1 (-1700 3400)(-1900 3400);
WIRE 16 -1 (-1700 3350)(-1900 3350);
WIRE 16 -1 (-1700 3300)(-1900 3300);
WIRE 16 -1 (-1700 3250)(-1900 3250);
WIRE 16 -1 (-1700 3200)(-1900 3200);
WIRE 16 -1 (-1700 3450)(-1900 3450);
WIRE 16 -1 (-1700 3500)(-1900 3500);
WIRE 16 -1 (-1700 4000)(-1900 4000);
WIRE 16 -1 (-1700 3950)(-1900 3950);
WIRE 16 -1 (-1700 3900)(-1900 3900);
WIRE 16 -1 (-1700 3850)(-1900 3850);
WIRE 16 -1 (-1700 3800)(-1900 3800);
WIRE 16 -1 (-1700 3750)(-1900 3750);
WIRE 16 -1 (-1700 3700)(-1900 3700);
WIRE 16 -1 (-1700 3650)(-1900 3650);
WIRE 16 -1 (-1700 3600)(-1900 3600);
WIRE 16 -1 (-1700 4050)(-1900 4050);
WIRE 16 -1 (-2900 4600)(-3100 4600);
WIRE 16 -1 (-2900 4650)(-3100 4650);
WIRE 16 -1 (-2900 4850)(-3100 4850);
WIRE 16 -1 (-2900 4150)(-3100 4150);
WIRE 16 -1 (-2900 4200)(-3100 4200);
WIRE 16 -1 (-2900 4250)(-3100 4250);
WIRE 16 -1 (-2900 4300)(-3100 4300);
WIRE 16 -1 (-2900 4350)(-3100 4350);
WIRE 16 -1 (-2900 4400)(-3100 4400);
WIRE 16 -1 (-2900 4450)(-3100 4450);
WIRE 16 -1 (-2900 4100)(-3100 4100);
WIRE 16 -1 (-2900 4500)(-3100 4500);
WIRE 16 -1 (-2900 4550)(-3100 4550);
WIRE 16 -1 (-2900 4700)(-3100 4700);
WIRE 16 -1 (-2900 4750)(-3100 4750);
WIRE 16 -1 (-2900 4800)(-3100 4800);
WIRE 16 -1 (-1700 4500)(-1900 4500);
WIRE 16 -1 (-1700 4450)(-1900 4450);
WIRE 16 -1 (-1700 4550)(-1900 4550);
WIRE 16 -1 (-1700 4600)(-1900 4600);
WIRE 16 -1 (-1700 4400)(-1900 4400);
WIRE 16 -1 (-1700 4350)(-1900 4350);
WIRE 16 -1 (-1700 4300)(-1900 4300);
WIRE 16 -1 (-1700 4250)(-1900 4250);
WIRE 16 -1 (-1700 4200)(-1900 4200);
WIRE 16 -1 (-1700 4150)(-1900 4150);
WIRE 16 -1 (-1700 4100)(-1900 4100);
WIRE 16 -1 (-1700 4850)(-1900 4850);
WIRE 16 -1 (-1700 4800)(-1900 4800);
WIRE 16 -1 (-1700 4750)(-1900 4750);
WIRE 16 -1 (-1700 4700)(-1900 4700);
WIRE 16 -1 (-1700 4650)(-1900 4650);
WIRE 16 -1 (850 3400)(450 3400);
WIRE 16 -1 (650 3450)(450 3450);
WIRE 16 -1 (850 3500)(450 3500);
WIRE 16 -1 (650 3550)(450 3550);
WIRE 16 -1 (850 3600)(450 3600);
WIRE 16 -1 (650 3650)(450 3650);
WIRE 16 -1 (850 3700)(450 3700);
WIRE 16 -1 (650 3750)(450 3750);
WIRE 16 -1 (850 3800)(450 3800);
WIRE 16 -1 (650 3850)(450 3850);
WIRE 16 -1 (850 3900)(450 3900);
WIRE 16 -1 (650 3950)(450 3950);
WIRE 16 -1 (850 4000)(450 4000);
WIRE 16 -1 (650 4050)(450 4050);
WIRE 16 -1 (850 4400)(450 4400);
WIRE 16 -1 (650 4450)(450 4450);
WIRE 16 -1 (850 4500)(450 4500);
WIRE 16 -1 (650 4550)(450 4550);
WIRE 16 -1 (850 4600)(450 4600);
WIRE 16 -1 (650 4650)(450 4650);
WIRE 16 -1 (850 4700)(450 4700);
WIRE 16 -1 (650 4750)(450 4750);
WIRE 16 -1 (850 4800)(450 4800);
WIRE 16 -1 (650 4850)(450 4850);
WIRE 16 -1 (850 4900)(450 4900);
WIRE 16 -1 (650 4950)(450 4950);
WIRE 16 -1 (850 5000)(450 5000);
WIRE 16 -1 (650 5050)(450 5050);
WIRE 16 -1 (850 5100)(450 5100);
WIRE 16 -1 (850 4100)(450 4100);
WIRE 16 -1 (650 4150)(450 4150);
WIRE 16 -1 (850 4200)(450 4200);
WIRE 16 -1 (650 4250)(450 4250);
WIRE 16 -1 (850 4300)(450 4300);
WIRE 16 -1 (650 4350)(450 4350);
WIRE 16 -1 (650 5150)(450 5150);
DOT 1 (1100 2950);
DOT 1 (-800 2550);
DOT 1 (-4650 1700);
DOT 1 (1100 3250);
DOT 1 (-3100 2000);
DOT 1 (1100 2500);
DOT 1 (1100 1550);
DOT 1 (1100 1650);
DOT 1 (1100 1600);
DOT 1 (1100 1700);
DOT 1 (1100 1800);
DOT 1 (1100 1750);
DOT 1 (1100 1850);
DOT 1 (1100 1900);
DOT 1 (1100 1950);
DOT 1 (1100 2050);
DOT 1 (1100 2000);
DOT 1 (1100 2100);
DOT 1 (1100 2250);
DOT 1 (1100 2300);
DOT 1 (1100 2400);
DOT 1 (1100 2550);
DOT 1 (1100 2600);
DOT 1 (1100 2700);
DOT 1 (1100 2800);
DOT 1 (1100 2850);
DOT 1 (1100 2900);
DOT 1 (1100 3000);
DOT 1 (1100 3050);
DOT 1 (1100 3100);
DOT 1 (1100 3200);
DOT 1 (1100 3150);
DOT 1 (1100 3350);
DOT 1 (1100 3300);
DOT 1 (1100 3400);
DOT 1 (1100 3450);
DOT 1 (1100 3500);
DOT 1 (1100 3600);
DOT 1 (1100 3550);
DOT 1 (1100 3650);
DOT 1 (1100 3700);
DOT 1 (2500 1450);
DOT 1 (2500 1550);
DOT 1 (2500 1500);
DOT 1 (2500 1650);
DOT 1 (2500 1600);
DOT 1 (2500 1700);
DOT 1 (2500 1800);
DOT 1 (2500 1750);
DOT 1 (2500 1850);
DOT 1 (2500 1950);
DOT 1 (2500 2000);
DOT 1 (2500 2050);
DOT 1 (2500 2100);
DOT 1 (2500 2150);
DOT 1 (2500 2200);
DOT 1 (2500 2250);
DOT 1 (2500 2300);
DOT 1 (2500 2350);
DOT 1 (2500 2450);
DOT 1 (2500 2400);
DOT 1 (2500 2500);
DOT 1 (2500 2550);
DOT 1 (2500 2600);
DOT 1 (2500 2700);
DOT 1 (2500 2650);
DOT 1 (2500 2750);
DOT 1 (2500 2800);
DOT 1 (2500 2850);
DOT 1 (2500 2950);
DOT 1 (2500 2900);
DOT 1 (2500 3000);
DOT 1 (2500 3050);
DOT 1 (2500 3100);
DOT 1 (2500 3150);
DOT 1 (2500 3250);
DOT 1 (2500 3200);
DOT 1 (2500 3350);
DOT 1 (2500 3300);
DOT 1 (2500 3400);
DOT 1 (2500 3450);
DOT 1 (2500 3500);
DOT 1 (2500 3550);
DOT 1 (2500 3600);
DOT 1 (2500 3650);
DOT 1 (2500 3700);
DOT 1 (1100 1500);
DOT 1 (1100 2450);
DOT 1 (1100 2350);
DOT 1 (-800 2700);
DOT 1 (-800 2750);
DOT 1 (-800 2850);
DOT 1 (-800 2800);
DOT 1 (-800 2250);
DOT 1 (-800 2200);
DOT 1 (-800 2300);
DOT 1 (-800 2350);
DOT 1 (-800 2400);
DOT 1 (-800 2150);
DOT 1 (-800 1750);
DOT 1 (-800 1800);
DOT 1 (-800 1850);
DOT 1 (-800 1900);
DOT 1 (-800 1950);
DOT 1 (-800 2050);
DOT 1 (-800 2000);
DOT 1 (-800 2100);
DOT 1 (-800 1650);
DOT 1 (-800 1200);
DOT 1 (-800 1250);
DOT 1 (-800 1350);
DOT 1 (-800 1450);
DOT 1 (-800 1500);
DOT 1 (-800 1550);
DOT 1 (-800 1400);
DOT 1 (-800 1600);
DOT 1 (-800 1300);
DOT 1 (-800 1700);
DOT 1 (1100 2750);
DOT 1 (600 2850);
DOT 1 (1100 2150);
DOT 1 (1100 2200);
DOT 1 (1100 1450);
DOT 1 (2500 1900);
DOT 1 (1100 2650);
DOT 1 (-3100 2050);
FORCENOTE
SMBUS ADDR: 0XAA
(-5286 742) 0;
DISPLAY LEFT (-5286 742);
DISPLAY 1.574468 (-5286 742);
PAINT PURPLE (-5286 742);
FORCENOTE
PLACE CAP NEAR DIMM CONNECTOR
(-5288 927) 0;
DISPLAY LEFT (-5288 927);
DISPLAY 1.595745 (-5288 927);
PAINT PURPLE (-5288 927);
QUIT
